.HEADER
BOARD_FILE 3.0 "Creo Elements/Pro 5.0 M210" 2017/06/07.10:01:35 3
16317-1                                 MM        
.END_HEADER
.BOARD_OUTLINE  MCAD
2.36000             
         0           473.75000           385.00000             0.00000
         0           473.75000           383.30000             0.00000
         0           472.75000           382.30000           -90.00000
         0           466.25000           382.30000             0.00000
         0           465.25000           383.30000           -90.00000
         0           465.25000           385.00000             0.00000
         0           464.25000           386.00000            90.00000
         0           418.70000           386.00000             0.00000
         0           417.70000           385.00000            90.00000
         0           417.70000           381.00000             0.00000
         0           416.70000           380.00000           -90.00000
         0           364.70000           380.00000             0.00000
         0           363.70000           381.00000           -90.00000
         0           363.70000           385.00000             0.00000
         0           362.70000           386.00000            90.00000
         0           317.15000           386.00000             0.00000
         0           316.15000           385.00000            90.00000
         0           316.15000           383.30000             0.00000
         0           315.15000           382.30000           -90.00000
         0           308.65000           382.30000             0.00000
         0           307.65000           383.30000           -90.00000
         0           307.65000           385.00000             0.00000
         0           306.65000           386.00000            90.00000
         0           280.16421           386.00000             0.00000
         0           279.45711           385.70711            45.00000
         0           277.04289           383.29289             0.00000
         0           276.75000           382.58579            45.00000
         0           276.75000           361.00000             0.00000
         0           275.75000           360.00000           -90.00000
         0           273.45000           360.00000             0.00000
         0           272.45000           361.00000           -90.00000
         0           272.45000           382.58579             0.00000
         0           272.15711           383.29289            45.00000
         0           269.74289           385.70711             0.00000
         0           269.03579           386.00000            45.00000
         0           253.00000           386.00000             0.00000
         0           252.00000           385.00000            90.00000
         0           252.00000           381.00000             0.00000
         0           251.00000           380.00000           -90.00000
         0           199.00000           380.00000             0.00000
         0           198.00000           381.00000           -90.00000
         0           198.00000           385.00000             0.00000
         0           197.00000           386.00000            90.00000
         0           183.35000           386.00000             0.00000
         0           182.35000           385.00000            90.00000
         0           182.35000           383.30000             0.00000
         0           181.35000           382.30000           -90.00000
         0           174.85000           382.30000             0.00000
         0           173.85000           383.30000           -90.00000
         0           173.85000           385.00000             0.00000
         0           172.85000           386.00000            90.00000
         0           127.30000           386.00000             0.00000
         0           126.30000           385.00000            90.00000
         0           126.30000           381.00000             0.00000
         0           125.30000           380.00000           -90.00000
         0            73.30000           380.00000             0.00000
         0            72.30000           381.00000           -90.00000
         0            72.30000           385.00000             0.00000
         0            71.30000           386.00000            90.00000
         0            25.75000           386.00000             0.00000
         0            24.75000           385.00000            90.00000
         0            24.75000           383.30000             0.00000
         0            23.75000           382.30000           -90.00000
         0            17.25000           382.30000             0.00000
         0            16.25000           383.30000           -90.00000
         0            16.25000           385.00000             0.00000
         0            15.25000           386.00000            90.00000
         0             4.00000           386.00000             0.00000
         0             3.00000           385.00000            90.00000
         0             3.00000           372.00000             0.00000
         0             2.00000           371.00000           -90.00000
         0             1.00000           371.00000             0.00000
         0             0.00000           370.00000            90.00000
         0            -0.00000             1.00000             0.00000
         0             1.00000             0.00000            90.00000
         0           198.00000            -0.00000             0.00000
         0           199.00000             1.00000            90.00000
         0           199.00000            47.20000             0.00000
         0           200.00000            48.20000           -90.00000
         0           206.00000            48.20000             0.00000
         0           207.00000            49.20000            90.00000
         0           207.00000            62.00000             0.00000
         0           208.00000            63.00000           -90.00000
         0           268.00000            63.00000             0.00000
         0           269.00000            62.00000           -90.00000
         0           269.00000            49.20000             0.00000
         0           270.00000            48.20000            90.00000
         0           310.00000            48.20000             0.00000
         0           311.00000            47.20000           -90.00000
         0           311.00000             1.00000             0.00000
         0           312.00000             0.00000            90.00000
         0           490.45000            -0.00000             0.00000
         0           491.45000             1.00000            90.00000
         0           491.45000           370.00000             0.00000
         0           490.45000           371.00000            90.00000
         0           489.45000           371.00000             0.00000
         0           488.45000           372.00000           -90.00000
         0           488.45000           385.00000             0.00000
         0           487.45000           386.00000            90.00000
         0           474.75000           386.00000             0.00000
         0           473.75000           385.00000            90.00000
         1            29.03103            67.23683             0.00000
         1            30.78997            70.57209            21.73429
         1            35.86003            70.57209          -146.12196
         1            37.61897            67.23683            21.73429
         1            29.03103            67.23683          -257.34662
         2            92.03103            67.23683             0.00000
         2            93.78997            70.57209            21.73429
         2            98.86003            70.57209          -146.12196
         2           100.61897            67.23683            21.73429
         2            92.03103            67.23683          -257.34662
         3           155.03103            67.23683             0.00000
         3           156.78997            70.57209            21.73429
         3           161.86003            70.57209          -146.12196
         3           163.61897            67.23683            21.73429
         3           155.03103            67.23683          -257.34662
         4            29.03103           182.23683             0.00000
         4            30.78997           185.57209            21.73429
         4            35.86003           185.57209          -146.12196
         4            37.61897           182.23683            21.73429
         4            29.03103           182.23683          -257.34662
         5            92.03103           182.23683             0.00000
         5            93.78997           185.57209            21.73429
         5            98.86003           185.57209          -146.12196
         5           100.61897           182.23683            21.73429
         5            92.03103           182.23683          -257.34662
         6           155.03103           182.23683             0.00000
         6           156.78997           185.57209            21.73429
         6           161.86003           185.57209          -146.12196
         6           163.61897           182.23683            21.73429
         6           155.03103           182.23683          -257.34662
         7            29.03103           297.23683             0.00000
         7            30.78997           300.57209            21.73429
         7            35.86003           300.57209          -146.12196
         7            37.61897           297.23683            21.73429
         7            29.03103           297.23683          -257.34662
         8            92.03103           297.23683             0.00000
         8            93.78997           300.57209            21.73429
         8            98.86003           300.57209          -146.12196
         8           100.61897           297.23683            21.73429
         8            92.03103           297.23683          -257.34662
         9           155.03103           297.23683             0.00000
         9           156.78997           300.57209            21.73429
         9           161.86003           300.57209          -146.12196
         9           163.61897           297.23683            21.73429
         9           155.03103           297.23683          -257.34662
        10           326.38103            67.23683             0.00000
        10           328.13997            70.57209            21.73429
        10           333.21003            70.57209          -146.12196
        10           334.96897            67.23683            21.73429
        10           326.38103            67.23683          -257.34662
        11           389.38103            67.23683             0.00000
        11           391.13997            70.57209            21.73429
        11           396.21003            70.57209          -146.12196
        11           397.96897            67.23683            21.73429
        11           389.38103            67.23683          -257.34662
        12           452.38103            67.23683             0.00000
        12           454.13997            70.57209            21.73429
        12           459.21003            70.57209          -146.12196
        12           460.96897            67.23683            21.73429
        12           452.38103            67.23683          -257.34662
        13           326.38103           182.23683             0.00000
        13           328.13997           185.57209            21.73429
        13           333.21003           185.57209          -146.12196
        13           334.96897           182.23683            21.73429
        13           326.38103           182.23683          -257.34662
        14           389.38103           182.23683             0.00000
        14           391.13997           185.57209            21.73429
        14           396.21003           185.57209          -146.12196
        14           397.96897           182.23683            21.73429
        14           389.38103           182.23683          -257.34662
        15           452.38103           182.23683             0.00000
        15           454.13997           185.57209            21.73429
        15           459.21003           185.57209          -146.12196
        15           460.96897           182.23683            21.73429
        15           452.38103           182.23683          -257.34662
        16           326.38103           297.23683             0.00000
        16           328.13997           300.57209            21.73429
        16           333.21003           300.57209          -146.12196
        16           334.96897           297.23683            21.73429
        16           326.38103           297.23683          -257.34662
        17           389.38103           297.23683             0.00000
        17           391.13997           300.57209            21.73429
        17           396.21003           300.57209          -146.12196
        17           397.96897           297.23683            21.73429
        17           389.38103           297.23683          -257.34662
        18           452.38103           297.23683             0.00000
        18           454.13997           300.57209            21.73429
        18           459.21003           300.57209          -146.12196
        18           460.96897           297.23683            21.73429
        18           452.38103           297.23683          -257.34662
        19           295.90603            97.43683             0.00000
        19           297.66497           100.77209            21.73429
        19           302.73503           100.77209          -146.12196
        19           304.49397            97.43683            21.73429
        19           295.90603            97.43683          -257.34662
        20           185.50603            97.43683             0.00000
        20           187.26497           100.77209            21.73429
        20           192.33503           100.77209          -146.12196
        20           194.09397            97.43683            21.73429
        20           185.50603            97.43683          -257.34662
        21           185.50603           207.43683             0.00000
        21           187.26497           210.77209            21.73429
        21           192.33503           210.77209          -146.12196
        21           194.09397           207.43683            21.73429
        21           185.50603           207.43683          -257.34662
        22           239.90603           247.43683             0.00000
        22           241.66497           250.77209            21.73429
        22           246.73503           250.77209          -146.12196
        22           248.49397           247.43683            21.73429
        22           239.90603           247.43683          -257.34662
        23           295.90603           247.43683             0.00000
        23           297.66497           250.77209            21.73429
        23           302.73503           250.77209          -146.12196
        23           304.49397           247.43683            21.73429
        23           295.90603           247.43683          -257.34662
        24           239.90603           179.23683             0.00000
        24           241.66497           182.57209            21.73429
        24           246.73503           182.57209          -146.12196
        24           248.49397           179.23683            21.73429
        24           239.90603           179.23683          -257.34662
        25           128.67500           335.40000             0.00000
        25           131.16500           335.40000          -180.00000
        25           128.67500           335.40000          -180.00000
        26           133.41000           335.40000             0.00000
        26           136.59000           335.40000          -180.00000
        26           133.41000           335.40000          -180.00000
        27            66.45500           335.40000             0.00000
        27            68.94500           335.40000          -180.00000
        27            66.45500           335.40000          -180.00000
        28            61.03000           335.40000             0.00000
        28            64.21000           335.40000          -180.00000
        28            61.03000           335.40000          -180.00000
        29           339.52500            14.00000             0.00000
        29           343.07500            14.00000          -180.00000
        29           339.52500            14.00000          -180.00000
        30            42.22500            14.00000             0.00000
        30            45.77500            14.00000          -180.00000
        30            42.22500            14.00000          -180.00000
        31           105.32500            24.00000             0.00000
        31           108.87500            24.00000          -180.00000
        31           105.32500            24.00000          -180.00000
        32           168.42500            14.00000             0.00000
        32           171.97500            14.00000          -180.00000
        32           168.42500            14.00000          -180.00000
        33           465.72500            14.00000             0.00000
        33           469.27500            14.00000          -180.00000
        33           465.72500            14.00000          -180.00000
        34           402.62500            24.00000             0.00000
        34           406.17500            24.00000          -180.00000
        34           402.62500            24.00000          -180.00000
        35            42.60000            31.00000             0.00000
        35            45.40000            31.00000          -180.00000
        35            42.60000            31.00000          -180.00000
        36           168.80000            31.00000             0.00000
        36           171.60000            31.00000          -180.00000
        36           168.80000            31.00000          -180.00000
        37           339.90000            31.00000             0.00000
        37           342.70000            31.00000          -180.00000
        37           339.90000            31.00000          -180.00000
        38           466.10000            31.00000             0.00000
        38           468.90000            31.00000          -180.00000
        38           466.10000            31.00000          -180.00000
        39           280.55000           293.46000             0.00000
        39           280.55000           296.96000          -180.00000
        39           280.55000           293.46000          -180.00000
        40           430.32500            66.80000             0.00000
        40           420.02500            66.80000          -180.00000
        40           430.32500            66.80000          -180.00000
        41           132.97500           181.80000             0.00000
        41           122.67500           181.80000          -180.00000
        41           132.97500           181.80000          -180.00000
.END_BOARD_OUTLINE
.DRILLED_HOLES
.END_DRILLED_HOLES
.PLACE_KEEPOUT      UNOWNED
TOP 0.00000        
         0           166.32500            63.80000             0.00000
         0           166.32500            69.80000             0.00000
         0           152.32500            69.80000           180.00000
         0           152.32500            63.80000             0.00000
         0           166.32500            63.80000           180.00000
.END_PLACE_KEEPOUT
.PLACE_KEEPOUT      UNOWNED
TOP 0.00000        
         0           103.32500            63.80000             0.00000
         0           103.32500            69.80000             0.00000
         0            89.32500            69.80000           180.00000
         0            89.32500            63.80000             0.00000
         0           103.32500            63.80000           180.00000
.END_PLACE_KEEPOUT
.PLACE_KEEPOUT      UNOWNED
TOP 0.00000        
         0            40.32500            63.80000             0.00000
         0            40.32500            69.80000             0.00000
         0            26.32500            69.80000           180.00000
         0            26.32500            63.80000             0.00000
         0            40.32500            63.80000           180.00000
.END_PLACE_KEEPOUT
.PLACE_KEEPOUT      UNOWNED
TOP 0.00000        
         0           196.80000            94.00000             0.00000
         0           196.80000           100.00000             0.00000
         0           182.80000           100.00000           180.00000
         0           182.80000            94.00000             0.00000
         0           196.80000            94.00000           180.00000
.END_PLACE_KEEPOUT
.PLACE_KEEPOUT      UNOWNED
TOP 0.00000        
         0           307.20000            94.00000             0.00000
         0           307.20000           100.00000             0.00000
         0           293.20000           100.00000           180.00000
         0           293.20000            94.00000             0.00000
         0           307.20000            94.00000           180.00000
.END_PLACE_KEEPOUT
.PLACE_KEEPOUT      UNOWNED
TOP 0.00000        
         0           337.67500            63.80000             0.00000
         0           337.67500            69.80000             0.00000
         0           323.67500            69.80000           180.00000
         0           323.67500            63.80000             0.00000
         0           337.67500            63.80000           180.00000
.END_PLACE_KEEPOUT
.PLACE_KEEPOUT      UNOWNED
TOP 0.00000        
         0           400.67500            63.80000             0.00000
         0           400.67500            69.80000             0.00000
         0           386.67500            69.80000           180.00000
         0           386.67500            63.80000             0.00000
         0           400.67500            63.80000           180.00000
.END_PLACE_KEEPOUT
.PLACE_KEEPOUT      UNOWNED
TOP 0.00000        
         0           463.67500            63.80000             0.00000
         0           463.67500            69.80000             0.00000
         0           449.67500            69.80000           180.00000
         0           449.67500            63.80000             0.00000
         0           463.67500            63.80000           180.00000
.END_PLACE_KEEPOUT
.PLACE_KEEPOUT      UNOWNED
TOP 0.00000        
         0           166.32500           178.80000             0.00000
         0           166.32500           184.80000             0.00000
         0           152.32500           184.80000           180.00000
         0           152.32500           178.80000             0.00000
         0           166.32500           178.80000           180.00000
.END_PLACE_KEEPOUT
.PLACE_KEEPOUT      UNOWNED
TOP 0.00000        
         0           103.32500           178.80000             0.00000
         0           103.32500           184.80000             0.00000
         0            89.32500           184.80000           180.00000
         0            89.32500           178.80000             0.00000
         0           103.32500           178.80000           180.00000
.END_PLACE_KEEPOUT
.PLACE_KEEPOUT      UNOWNED
TOP 0.00000        
         0            40.32500           178.80000             0.00000
         0            40.32500           184.80000             0.00000
         0            26.32500           184.80000           180.00000
         0            26.32500           178.80000             0.00000
         0            40.32500           178.80000           180.00000
.END_PLACE_KEEPOUT
.PLACE_KEEPOUT      UNOWNED
TOP 0.00000        
         0           196.80000           204.00000             0.00000
         0           196.80000           210.00000             0.00000
         0           182.80000           210.00000           180.00000
         0           182.80000           204.00000             0.00000
         0           196.80000           204.00000           180.00000
.END_PLACE_KEEPOUT
.PLACE_KEEPOUT      UNOWNED
TOP 0.00000        
         0           251.20000           175.80000             0.00000
         0           251.20000           181.80000             0.00000
         0           237.20000           181.80000           180.00000
         0           237.20000           175.80000             0.00000
         0           251.20000           175.80000           180.00000
.END_PLACE_KEEPOUT
.PLACE_KEEPOUT      UNOWNED
TOP 0.00000        
         0           337.67500           178.80000             0.00000
         0           337.67500           184.80000             0.00000
         0           323.67500           184.80000           180.00000
         0           323.67500           178.80000             0.00000
         0           337.67500           178.80000           180.00000
.END_PLACE_KEEPOUT
.PLACE_KEEPOUT      UNOWNED
TOP 0.00000        
         0           463.67500           178.80000             0.00000
         0           463.67500           184.80000             0.00000
         0           449.67500           184.80000           180.00000
         0           449.67500           178.80000             0.00000
         0           463.67500           178.80000           180.00000
.END_PLACE_KEEPOUT
.PLACE_KEEPOUT      UNOWNED
TOP 0.00000        
         0           400.67500           178.80000             0.00000
         0           400.67500           184.80000             0.00000
         0           386.67500           184.80000           180.00000
         0           386.67500           178.80000             0.00000
         0           400.67500           178.80000           180.00000
.END_PLACE_KEEPOUT
.PLACE_KEEPOUT      UNOWNED
TOP 0.00000        
         0           307.20000           244.00000             0.00000
         0           307.20000           250.00000             0.00000
         0           293.20000           250.00000           180.00000
         0           293.20000           244.00000             0.00000
         0           307.20000           244.00000           180.00000
.END_PLACE_KEEPOUT
.PLACE_KEEPOUT      UNOWNED
TOP 0.00000        
         0           251.20000           244.00000             0.00000
         0           251.20000           250.00000             0.00000
         0           237.20000           250.00000           180.00000
         0           237.20000           244.00000             0.00000
         0           251.20000           244.00000           180.00000
.END_PLACE_KEEPOUT
.PLACE_KEEPOUT      UNOWNED
TOP 0.00000        
         0           337.67500           293.80000             0.00000
         0           337.67500           299.80000             0.00000
         0           323.67500           299.80000           180.00000
         0           323.67500           293.80000             0.00000
         0           337.67500           293.80000           180.00000
.END_PLACE_KEEPOUT
.PLACE_KEEPOUT      UNOWNED
TOP 0.00000        
         0           400.67500           293.80000             0.00000
         0           400.67500           299.80000             0.00000
         0           386.67500           299.80000           180.00000
         0           386.67500           293.80000             0.00000
         0           400.67500           293.80000           180.00000
.END_PLACE_KEEPOUT
.PLACE_KEEPOUT      UNOWNED
TOP 0.00000        
         0           463.67500           293.80000             0.00000
         0           463.67500           299.80000             0.00000
         0           449.67500           299.80000           180.00000
         0           449.67500           293.80000             0.00000
         0           463.67500           293.80000           180.00000
.END_PLACE_KEEPOUT
.PLACE_KEEPOUT      UNOWNED
TOP 0.00000        
         0           166.32500           293.80000             0.00000
         0           166.32500           299.80000             0.00000
         0           152.32500           299.80000           180.00000
         0           152.32500           293.80000             0.00000
         0           166.32500           293.80000           180.00000
.END_PLACE_KEEPOUT
.PLACE_KEEPOUT      UNOWNED
TOP 0.00000        
         0           103.32500           293.80000             0.00000
         0           103.32500           299.80000             0.00000
         0            89.32500           299.80000           180.00000
         0            89.32500           293.80000             0.00000
         0           103.32500           293.80000           180.00000
.END_PLACE_KEEPOUT
.PLACE_KEEPOUT      UNOWNED
TOP 0.00000        
         0            40.32500           293.80000             0.00000
         0            40.32500           299.80000             0.00000
         0            26.32500           299.80000           180.00000
         0            26.32500           293.80000             0.00000
         0            40.32500           293.80000           180.00000
.END_PLACE_KEEPOUT
.PLACE_KEEPOUT      UNOWNED
TOP 0.00000        
         0           462.75000            14.00000             0.00000
         0           472.25000            14.00000           180.00000
         0           462.75000            14.00000           180.00000
.END_PLACE_KEEPOUT
.PLACE_KEEPOUT      UNOWNED
TOP 0.00000        
         0           399.65000            24.00000             0.00000
         0           409.15000            24.00000           180.00000
         0           399.65000            24.00000           180.00000
.END_PLACE_KEEPOUT
.PLACE_KEEPOUT      UNOWNED
TOP 0.00000        
         0           336.55000            14.00000             0.00000
         0           346.05000            14.00000           180.00000
         0           336.55000            14.00000           180.00000
.END_PLACE_KEEPOUT
.PLACE_KEEPOUT      UNOWNED
TOP 0.00000        
         0           165.45000            14.00000             0.00000
         0           174.95000            14.00000           180.00000
         0           165.45000            14.00000           180.00000
.END_PLACE_KEEPOUT
.PLACE_KEEPOUT      UNOWNED
TOP 0.00000        
         0           102.35000            24.00000             0.00000
         0           111.85000            24.00000           180.00000
         0           102.35000            24.00000           180.00000
.END_PLACE_KEEPOUT
.PLACE_KEEPOUT      UNOWNED
TOP 0.00000        
         0            39.25000            14.00000             0.00000
         0            48.75000            14.00000           180.00000
         0            39.25000            14.00000           180.00000
.END_PLACE_KEEPOUT
.PLACE_KEEPOUT      UNOWNED
TOP 0.20000        
         0           177.30000            84.00000             0.00000
         0           177.30000           110.00000             0.00000
         0           202.30000           110.00000             0.00000
         0           202.30000            84.00000             0.00000
         0           177.30000            84.00000             0.00000
.END_PLACE_KEEPOUT
.PLACE_KEEPOUT      UNOWNED
TOP 0.20000        
         0           287.70000            84.00000             0.00000
         0           287.70000           110.00000             0.00000
         0           312.70000           110.00000             0.00000
         0           312.70000            84.00000             0.00000
         0           287.70000            84.00000             0.00000
.END_PLACE_KEEPOUT
.PLACE_KEEPOUT      UNOWNED
TOP 0.20000        
         0           256.20000           165.80000             0.00000
         0           256.20000           191.80000             0.00000
         0           231.20000           191.80000             0.00000
         0           231.20000           165.80000             0.00000
         0           256.20000           165.80000             0.00000
.END_PLACE_KEEPOUT
.PLACE_KEEPOUT      UNOWNED
TOP 0.20000        
         0           177.30000           220.00000             0.00000
         0           202.30000           220.00000             0.00000
         0           202.30000           194.00000             0.00000
         0           177.30000           194.00000             0.00000
         0           177.30000           220.00000             0.00000
.END_PLACE_KEEPOUT
.PLACE_KEEPOUT      UNOWNED
TOP 0.20000        
         0           256.20000           234.00000             0.00000
         0           256.20000           260.00000             0.00000
         0           231.20000           260.00000             0.00000
         0           231.20000           234.00000             0.00000
         0           256.20000           234.00000             0.00000
.END_PLACE_KEEPOUT
.PLACE_KEEPOUT      UNOWNED
TOP 0.20000        
         0           312.70000           234.00000             0.00000
         0           287.70000           234.00000             0.00000
         0           287.70000           260.00000             0.00000
         0           312.70000           260.00000             0.00000
         0           312.70000           234.00000             0.00000
.END_PLACE_KEEPOUT
.PLACE_KEEPOUT      UNOWNED
TOP 0.20000        
         0           126.30000           370.00000             0.00000
         0            72.30000           370.00000             0.00000
         0            72.30000           380.00000             0.00000
         0           126.30000           380.00000             0.00000
         0           126.30000           370.00000             0.00000
.END_PLACE_KEEPOUT
.PLACE_KEEPOUT      UNOWNED
TOP 0.20000        
         0           252.00000           370.00000             0.00000
         0           252.00000           380.00000             0.00000
         0           198.00000           380.00000             0.00000
         0           198.00000           370.00000             0.00000
         0           252.00000           370.00000             0.00000
.END_PLACE_KEEPOUT
.PLACE_KEEPOUT      UNOWNED
TOP 0.20000        
         0           417.70000           370.00000             0.00000
         0           363.70000           370.00000             0.00000
         0           363.70000           380.00000             0.00000
         0           417.70000           380.00000             0.00000
         0           417.70000           370.00000             0.00000
.END_PLACE_KEEPOUT
.PLACE_KEEPOUT      UNOWNED
TOP 0.20000        
         0           293.20000            94.00000             0.00000
         0           307.20000            94.00000           180.00000
         0           307.20000           100.00000             0.00000
         0           293.20000           100.00000           180.00000
         0           293.20000            94.00000             0.00000
.END_PLACE_KEEPOUT
.PLACE_KEEPOUT      UNOWNED
TOP 0.20000        
         0           182.80000            94.00000             0.00000
         0           196.80000            94.00000           180.00000
         0           196.80000           100.00000             0.00000
         0           182.80000           100.00000           180.00000
         0           182.80000            94.00000             0.00000
.END_PLACE_KEEPOUT
.PLACE_KEEPOUT      UNOWNED
TOP 0.20000        
         0           237.20000           175.80000             0.00000
         0           251.20000           175.80000           180.00000
         0           251.20000           181.80000             0.00000
         0           237.20000           181.80000           180.00000
         0           237.20000           175.80000             0.00000
.END_PLACE_KEEPOUT
.PLACE_KEEPOUT      UNOWNED
TOP 0.20000        
         0           182.80000           204.00000             0.00000
         0           196.80000           204.00000           180.00000
         0           196.80000           210.00000             0.00000
         0           182.80000           210.00000           180.00000
         0           182.80000           204.00000             0.00000
.END_PLACE_KEEPOUT
.PLACE_KEEPOUT      UNOWNED
TOP 0.20000        
         0           237.20000           244.00000             0.00000
         0           251.20000           244.00000           180.00000
         0           251.20000           250.00000             0.00000
         0           237.20000           250.00000           180.00000
         0           237.20000           244.00000             0.00000
.END_PLACE_KEEPOUT
.PLACE_KEEPOUT      UNOWNED
TOP 0.20000        
         0           293.20000           244.00000             0.00000
         0           307.20000           244.00000           180.00000
         0           307.20000           250.00000             0.00000
         0           293.20000           250.00000           180.00000
         0           293.20000           244.00000             0.00000
.END_PLACE_KEEPOUT
.PLACE_KEEPOUT      UNOWNED
TOP 0.00000        
         0           141.82500           181.80000             0.00000
         0           113.82500           181.80000           180.00000
         0           141.82500           181.80000           180.00000
.END_PLACE_KEEPOUT
.PLACE_KEEPOUT      UNOWNED
TOP 0.00000        
         0           439.17500            66.80000             0.00000
         0           411.17500            66.80000           180.00000
         0           439.17500            66.80000           180.00000
.END_PLACE_KEEPOUT
.PLACE_KEEPOUT      UNOWNED
TOP 0.20000        
         0           180.65000           266.80000             0.00000
         0           180.65000           276.80000             0.00000
         0           191.80000           276.80000             0.00000
         0           191.80000           326.80000             0.00000
         0             0.00000           326.80000             0.00000
         0             0.00000           276.80000             0.00000
         0             8.35000           276.80000             0.00000
         0             8.35000           266.80000             0.00000
         0            22.90000           266.80000             0.00000
         0            22.90000           276.80000             0.00000
         0            39.90000           276.80000             0.00000
         0            39.90000           266.80000             0.00000
         0            54.45000           266.80000             0.00000
         0            54.45000           276.80000             0.00000
         0            71.45000           276.80000             0.00000
         0            71.45000           266.80000             0.00000
         0            86.00000           266.80000             0.00000
         0            86.00000           276.80000             0.00000
         0           103.00000           276.80000             0.00000
         0           103.00000           266.80000             0.00000
         0           117.55000           266.80000             0.00000
         0           117.55000           276.80000             0.00000
         0           134.55000           276.80000             0.00000
         0           134.55000           266.80000             0.00000
         0           149.10000           266.80000             0.00000
         0           149.10000           276.80000             0.00000
         0           166.10000           276.80000             0.00000
         0           166.10000           266.80000             0.00000
         0           180.65000           266.80000             0.00000
.END_PLACE_KEEPOUT
.PLACE_KEEPOUT      UNOWNED
TOP 0.20000        
         0           298.20000           276.80000             0.00000
         0           298.20000           326.80000             0.00000
         0           491.45000           326.80000             0.00000
         0           491.45000           276.80000             0.00000
         0           478.00000           276.80000             0.00000
         0           478.00000           266.80000             0.00000
         0           463.45000           266.80000             0.00000
         0           463.45000           276.80000             0.00000
         0           446.45000           276.80000             0.00000
         0           446.45000           266.80000             0.00000
         0           431.90000           266.80000             0.00000
         0           431.90000           276.80000             0.00000
         0           414.90000           276.80000             0.00000
         0           414.90000           266.80000             0.00000
         0           400.35000           266.80000             0.00000
         0           400.35000           276.80000             0.00000
         0           383.35000           276.80000             0.00000
         0           383.35000           266.80000             0.00000
         0           368.80000           266.80000             0.00000
         0           368.80000           276.80000             0.00000
         0           351.80000           276.80000             0.00000
         0           351.80000           266.80000             0.00000
         0           337.25000           266.80000             0.00000
         0           337.25000           276.80000             0.00000
         0           320.25000           276.80000             0.00000
         0           320.25000           266.80000             0.00000
         0           305.70000           266.80000             0.00000
         0           305.70000           276.80000             0.00000
         0           298.20000           276.80000             0.00000
.END_PLACE_KEEPOUT
.PLACE_KEEPOUT      UNOWNED
TOP 0.20000        
         0           177.30000           194.00000             0.00000
         0           177.30000           211.80000             0.00000
         0             0.00000           211.80000             0.00000
         0             0.00000           161.80000             0.00000
         0             8.35000           161.80000             0.00000
         0             8.35000           151.80000             0.00000
         0            22.90000           151.80000             0.00000
         0            22.90000           161.80000             0.00000
         0            39.90000           161.80000             0.00000
         0            39.90000           151.80000             0.00000
         0            54.45000           151.80000             0.00000
         0            54.45000           161.80000             0.00000
         0            71.45000           161.80000             0.00000
         0            71.45000           151.80000             0.00000
         0            86.00000           151.80000             0.00000
         0            86.00000           161.80000             0.00000
         0           103.00000           161.80000             0.00000
         0           103.00000           151.80000             0.00000
         0           117.55000           151.80000             0.00000
         0           117.55000           161.80000             0.00000
         0           134.55000           161.80000             0.00000
         0           134.55000           151.80000             0.00000
         0           149.10000           151.80000             0.00000
         0           149.10000           161.80000             0.00000
         0           166.10000           161.80000             0.00000
         0           166.10000           151.80000             0.00000
         0           180.65000           151.80000             0.00000
         0           180.65000           161.80000             0.00000
         0           191.80000           161.80000             0.00000
         0           191.80000           194.00000             0.00000
         0           177.30000           194.00000             0.00000
.END_PLACE_KEEPOUT
.PLACE_KEEPOUT      UNOWNED
TOP 0.20000        
         0           298.20000           211.80000             0.00000
         0           491.45000           211.80000             0.00000
         0           491.45000           161.80000             0.00000
         0           478.00000           161.80000             0.00000
         0           478.00000           151.80000             0.00000
         0           463.45000           151.80000             0.00000
         0           463.45000           161.80000             0.00000
         0           446.45000           161.80000             0.00000
         0           446.45000           151.80000             0.00000
         0           431.90000           151.80000             0.00000
         0           431.90000           161.80000             0.00000
         0           414.90000           161.80000             0.00000
         0           414.90000           151.80000             0.00000
         0           400.35000           151.80000             0.00000
         0           400.35000           161.80000             0.00000
         0           383.35000           161.80000             0.00000
         0           383.35000           151.80000             0.00000
         0           368.80000           151.80000             0.00000
         0           368.80000           161.80000             0.00000
         0           351.80000           161.80000             0.00000
         0           351.80000           151.80000             0.00000
         0           337.25000           151.80000             0.00000
         0           337.25000           161.80000             0.00000
         0           320.25000           161.80000             0.00000
         0           320.25000           151.80000             0.00000
         0           305.70000           151.80000             0.00000
         0           305.70000           161.80000             0.00000
         0           298.20000           161.80000             0.00000
         0           298.20000           211.80000             0.00000
.END_PLACE_KEEPOUT
.PLACE_KEEPOUT      UNOWNED
TOP 0.20000        
         0           177.30000            84.00000             0.00000
         0           177.30000            96.80000             0.00000
         0             0.00000            96.80000             0.00000
         0             0.00000            46.80000             0.00000
         0             8.35000            46.80000             0.00000
         0             8.35000            36.80000             0.00000
         0            22.90000            36.80000             0.00000
         0            22.90000            46.80000             0.00000
         0            39.90000            46.80000             0.00000
         0            39.90000            36.80000             0.00000
         0            54.45000            36.80000             0.00000
         0            54.45000            46.80000             0.00000
         0            71.45000            46.80000             0.00000
         0            71.45000            36.80000             0.00000
         0            86.00000            36.80000             0.00000
         0            86.00000            46.80000             0.00000
         0           103.00000            46.80000             0.00000
         0           103.00000            36.80000             0.00000
         0           117.55000            36.80000             0.00000
         0           117.55000            46.80000             0.00000
         0           134.55000            46.80000             0.00000
         0           134.55000            36.80000             0.00000
         0           149.10000            36.80000             0.00000
         0           149.10000            46.80000             0.00000
         0           166.10000            46.80000             0.00000
         0           166.10000            36.80000             0.00000
         0           180.65000            36.80000             0.00000
         0           180.65000            46.80000             0.00000
         0           191.80000            46.80000             0.00000
         0           191.80000            84.00000             0.00000
         0           177.30000            84.00000             0.00000
.END_PLACE_KEEPOUT
.PLACE_KEEPOUT      UNOWNED
TOP 0.20000        
         0           312.70000            96.80000             0.00000
         0           491.45000            96.80000             0.00000
         0           491.45000            46.80000             0.00000
         0           478.00000            46.80000             0.00000
         0           478.00000            36.80000             0.00000
         0           463.45000            36.80000             0.00000
         0           463.45000            46.80000             0.00000
         0           446.45000            46.80000             0.00000
         0           446.45000            36.80000             0.00000
         0           431.90000            36.80000             0.00000
         0           431.90000            46.80000             0.00000
         0           414.90000            46.80000             0.00000
         0           414.90000            36.80000             0.00000
         0           400.35000            36.80000             0.00000
         0           400.35000            46.80000             0.00000
         0           383.35000            46.80000             0.00000
         0           383.35000            36.80000             0.00000
         0           368.80000            36.80000             0.00000
         0           368.80000            46.80000             0.00000
         0           351.80000            46.80000             0.00000
         0           351.80000            36.80000             0.00000
         0           337.25000            36.80000             0.00000
         0           337.25000            46.80000             0.00000
         0           320.25000            46.80000             0.00000
         0           320.25000            36.80000             0.00000
         0           311.00000            36.80000             0.00000
         0           311.00000            47.20000             0.00000
         0           310.00000            48.20000            90.00000
         0           298.20000            48.20000             0.00000
         0           298.20000            84.00000             0.00000
         0           312.70000            84.00000             0.00000
         0           312.70000            96.80000             0.00000
.END_PLACE_KEEPOUT
.PLACE_KEEPOUT      UNOWNED
TOP 0.20000        
         0           449.67500            63.80000             0.00000
         0           449.67500            69.80000             0.00000
         0           463.67500            69.80000          -180.00000
         0           463.67500            63.80000             0.00000
         0           449.67500            63.80000          -180.00000
.END_PLACE_KEEPOUT
.PLACE_KEEPOUT      UNOWNED
TOP 0.20000        
         0           386.67500            63.80000             0.00000
         0           386.67500            69.80000             0.00000
         0           400.67500            69.80000          -180.00000
         0           400.67500            63.80000             0.00000
         0           386.67500            63.80000          -180.00000
.END_PLACE_KEEPOUT
.PLACE_KEEPOUT      UNOWNED
TOP 0.20000        
         0           323.67500            63.80000             0.00000
         0           323.67500            69.80000             0.00000
         0           337.67500            69.80000          -180.00000
         0           337.67500            63.80000             0.00000
         0           323.67500            63.80000          -180.00000
.END_PLACE_KEEPOUT
.PLACE_KEEPOUT      UNOWNED
TOP 0.20000        
         0           152.32500            63.80000             0.00000
         0           152.32500            69.80000             0.00000
         0           166.32500            69.80000          -180.00000
         0           166.32500            63.80000             0.00000
         0           152.32500            63.80000          -180.00000
.END_PLACE_KEEPOUT
.PLACE_KEEPOUT      UNOWNED
TOP 0.20000        
         0            89.32500            63.80000             0.00000
         0            89.32500            69.80000             0.00000
         0           103.32500            69.80000          -180.00000
         0           103.32500            63.80000             0.00000
         0            89.32500            63.80000          -180.00000
.END_PLACE_KEEPOUT
.PLACE_KEEPOUT      UNOWNED
TOP 0.20000        
         0            26.32500            63.80000             0.00000
         0            26.32500            69.80000             0.00000
         0            40.32500            69.80000          -180.00000
         0            40.32500            63.80000             0.00000
         0            26.32500            63.80000          -180.00000
.END_PLACE_KEEPOUT
.PLACE_KEEPOUT      UNOWNED
TOP 0.20000        
         0            26.32500           178.80000             0.00000
         0            26.32500           184.80000             0.00000
         0            40.32500           184.80000          -180.00000
         0            40.32500           178.80000             0.00000
         0            26.32500           178.80000          -180.00000
.END_PLACE_KEEPOUT
.PLACE_KEEPOUT      UNOWNED
TOP 0.20000        
         0            89.32500           178.80000             0.00000
         0            89.32500           184.80000             0.00000
         0           103.32500           184.80000          -180.00000
         0           103.32500           178.80000             0.00000
         0            89.32500           178.80000          -180.00000
.END_PLACE_KEEPOUT
.PLACE_KEEPOUT      UNOWNED
TOP 0.20000        
         0           152.32500           178.80000             0.00000
         0           152.32500           184.80000             0.00000
         0           166.32500           184.80000          -180.00000
         0           166.32500           178.80000             0.00000
         0           152.32500           178.80000          -180.00000
.END_PLACE_KEEPOUT
.PLACE_KEEPOUT      UNOWNED
TOP 0.20000        
         0           323.67500           178.80000             0.00000
         0           323.67500           184.80000             0.00000
         0           337.67500           184.80000          -180.00000
         0           337.67500           178.80000             0.00000
         0           323.67500           178.80000          -180.00000
.END_PLACE_KEEPOUT
.PLACE_KEEPOUT      UNOWNED
TOP 0.20000        
         0           386.67500           178.80000             0.00000
         0           386.67500           184.80000             0.00000
         0           400.67500           184.80000          -180.00000
         0           400.67500           178.80000             0.00000
         0           386.67500           178.80000          -180.00000
.END_PLACE_KEEPOUT
.PLACE_KEEPOUT      UNOWNED
TOP 0.20000        
         0           449.67500           178.80000             0.00000
         0           449.67500           184.80000             0.00000
         0           463.67500           184.80000          -180.00000
         0           463.67500           178.80000             0.00000
         0           449.67500           178.80000          -180.00000
.END_PLACE_KEEPOUT
.PLACE_KEEPOUT      UNOWNED
TOP 0.20000        
         0           323.67500           293.80000             0.00000
         0           323.67500           299.80000             0.00000
         0           337.67500           299.80000          -180.00000
         0           337.67500           293.80000             0.00000
         0           323.67500           293.80000          -180.00000
.END_PLACE_KEEPOUT
.PLACE_KEEPOUT      UNOWNED
TOP 0.20000        
         0           386.67500           293.80000             0.00000
         0           386.67500           299.80000             0.00000
         0           400.67500           299.80000          -180.00000
         0           400.67500           293.80000             0.00000
         0           386.67500           293.80000          -180.00000
.END_PLACE_KEEPOUT
.PLACE_KEEPOUT      UNOWNED
TOP 0.20000        
         0           449.67500           293.80000             0.00000
         0           449.67500           299.80000             0.00000
         0           463.67500           299.80000          -180.00000
         0           463.67500           293.80000             0.00000
         0           449.67500           293.80000          -180.00000
.END_PLACE_KEEPOUT
.PLACE_KEEPOUT      UNOWNED
TOP 0.20000        
         0           152.32500           293.80000             0.00000
         0           152.32500           299.80000             0.00000
         0           166.32500           299.80000          -180.00000
         0           166.32500           293.80000             0.00000
         0           152.32500           293.80000          -180.00000
.END_PLACE_KEEPOUT
.PLACE_KEEPOUT      UNOWNED
TOP 0.20000        
         0            89.32500           293.80000             0.00000
         0            89.32500           299.80000             0.00000
         0           103.32500           299.80000          -180.00000
         0           103.32500           293.80000             0.00000
         0            89.32500           293.80000          -180.00000
.END_PLACE_KEEPOUT
.PLACE_KEEPOUT      UNOWNED
TOP 0.20000        
         0            26.32500           293.80000             0.00000
         0            26.32500           299.80000             0.00000
         0            40.32500           299.80000          -180.00000
         0            40.32500           293.80000             0.00000
         0            26.32500           293.80000          -180.00000
.END_PLACE_KEEPOUT
.PLACE_KEEPOUT      UNOWNED
TOP 0.20000        
         0           113.82500           181.80000             0.00000
         0           141.82500           181.80000           180.00000
         0           113.82500           181.80000           180.00000
.END_PLACE_KEEPOUT
.PLACE_KEEPOUT      UNOWNED
TOP 0.20000        
         0           411.17500            66.80000             0.00000
         0           439.17500            66.80000           180.00000
         0           411.17500            66.80000           180.00000
.END_PLACE_KEEPOUT
.PLACE_KEEPOUT      UNOWNED
TOP 2.00000        
         0           491.45000           211.80000             0.00000
         0           491.45000           276.80000             0.00000
         0           478.00000           276.80000             0.00000
         0           478.00000           266.80000             0.00000
         0           463.45000           266.80000             0.00000
         0           463.45000           276.80000             0.00000
         0           446.45000           276.80000             0.00000
         0           446.45000           266.80000             0.00000
         0           431.90000           266.80000             0.00000
         0           431.90000           276.80000             0.00000
         0           414.90000           276.80000             0.00000
         0           414.90000           266.80000             0.00000
         0           400.35000           266.80000             0.00000
         0           400.35000           276.80000             0.00000
         0           383.35000           276.80000             0.00000
         0           383.35000           266.80000             0.00000
         0           368.80000           266.80000             0.00000
         0           368.80000           276.80000             0.00000
         0           351.80000           276.80000             0.00000
         0           351.80000           266.80000             0.00000
         0           337.25000           266.80000             0.00000
         0           337.25000           276.80000             0.00000
         0           320.25000           276.80000             0.00000
         0           320.25000           266.80000             0.00000
         0           305.70000           266.80000             0.00000
         0           305.70000           276.80000             0.00000
         0           298.20000           276.80000             0.00000
         0           298.20000           260.00000             0.00000
         0           312.70000           260.00000             0.00000
         0           312.70000           234.00000             0.00000
         0           298.20000           234.00000             0.00000
         0           298.20000           211.80000             0.00000
         0           491.45000           211.80000             0.00000
.END_PLACE_KEEPOUT
.PLACE_KEEPOUT      UNOWNED
TOP 2.00000        
         0           177.30000           211.80000             0.00000
         0           177.30000           220.00000             0.00000
         0           191.80000           220.00000             0.00000
         0           191.80000           276.80000             0.00000
         0           180.65000           276.80000             0.00000
         0           180.65000           266.80000             0.00000
         0           166.10000           266.80000             0.00000
         0           166.10000           276.80000             0.00000
         0           149.10000           276.80000             0.00000
         0           149.10000           266.80000             0.00000
         0           134.55000           266.80000             0.00000
         0           134.55000           276.80000             0.00000
         0           117.55000           276.80000             0.00000
         0           117.55000           266.80000             0.00000
         0           103.00000           266.80000             0.00000
         0           103.00000           276.80000             0.00000
         0            86.00000           276.80000             0.00000
         0            86.00000           266.80000             0.00000
         0            71.45000           266.80000             0.00000
         0            71.45000           276.80000             0.00000
         0            54.45000           276.80000             0.00000
         0            54.45000           266.80000             0.00000
         0            39.90000           266.80000             0.00000
         0            39.90000           276.80000             0.00000
         0            22.90000           276.80000             0.00000
         0            22.90000           266.80000             0.00000
         0             8.35000           266.80000             0.00000
         0             8.35000           276.80000             0.00000
         0             0.00000           276.80000             0.00000
         0             0.00000           211.80000             0.00000
         0           177.30000           211.80000             0.00000
.END_PLACE_KEEPOUT
.PLACE_KEEPOUT      UNOWNED
TOP 2.00000        
         0           177.30000            96.80000             0.00000
         0           177.30000           110.00000             0.00000
         0           191.80000           110.00000             0.00000
         0           191.80000           161.80000             0.00000
         0           180.65000           161.80000             0.00000
         0           180.65000           151.80000             0.00000
         0           166.10000           151.80000             0.00000
         0           166.10000           161.80000             0.00000
         0           149.10000           161.80000             0.00000
         0           149.10000           151.80000             0.00000
         0           134.55000           151.80000             0.00000
         0           134.55000           161.80000             0.00000
         0           117.55000           161.80000             0.00000
         0           117.55000           151.80000             0.00000
         0           103.00000           151.80000             0.00000
         0           103.00000           161.80000             0.00000
         0            86.00000           161.80000             0.00000
         0            86.00000           151.80000             0.00000
         0            71.45000           151.80000             0.00000
         0            71.45000           161.80000             0.00000
         0            54.45000           161.80000             0.00000
         0            54.45000           151.80000             0.00000
         0            39.90000           151.80000             0.00000
         0            39.90000           161.80000             0.00000
         0            22.90000           161.80000             0.00000
         0            22.90000           151.80000             0.00000
         0             8.35000           151.80000             0.00000
         0             8.35000           161.80000             0.00000
         0             0.00000           161.80000             0.00000
         0             0.00000            96.80000             0.00000
         0           177.30000            96.80000             0.00000
.END_PLACE_KEEPOUT
.PLACE_KEEPOUT      UNOWNED
TOP 2.00000        
         0           491.45000            96.80000             0.00000
         0           491.45000           161.80000             0.00000
         0           478.00000           161.80000             0.00000
         0           478.00000           151.80000             0.00000
         0           463.45000           151.80000             0.00000
         0           463.45000           161.80000             0.00000
         0           446.45000           161.80000             0.00000
         0           446.45000           151.80000             0.00000
         0           431.90000           151.80000             0.00000
         0           431.90000           161.80000             0.00000
         0           414.90000           161.80000             0.00000
         0           414.90000           151.80000             0.00000
         0           400.35000           151.80000             0.00000
         0           400.35000           161.80000             0.00000
         0           383.35000           161.80000             0.00000
         0           383.35000           151.80000             0.00000
         0           368.80000           151.80000             0.00000
         0           368.80000           161.80000             0.00000
         0           351.80000           161.80000             0.00000
         0           351.80000           151.80000             0.00000
         0           337.25000           151.80000             0.00000
         0           337.25000           161.80000             0.00000
         0           320.25000           161.80000             0.00000
         0           320.25000           151.80000             0.00000
         0           305.70000           151.80000             0.00000
         0           305.70000           161.80000             0.00000
         0           298.20000           161.80000             0.00000
         0           298.20000           110.00000             0.00000
         0           312.70000           110.00000             0.00000
         0           312.70000            96.80000             0.00000
         0           491.45000            96.80000             0.00000
.END_PLACE_KEEPOUT
.PLACE_KEEPOUT      UNOWNED
TOP 2.00000        
         0           191.80000            -0.00000             0.00000
         0           191.80000            46.80000             0.00000
         0           180.65000            46.80000             0.00000
         0           180.65000            36.80000             0.00000
         0           166.10000            36.80000             0.00000
         0           166.10000            46.80000             0.00000
         0           149.10000            46.80000             0.00000
         0           149.10000            36.80000             0.00000
         0           134.55000            36.80000             0.00000
         0           134.55000            46.80000             0.00000
         0           117.55000            46.80000             0.00000
         0           117.55000            36.80000             0.00000
         0           103.00000            36.80000             0.00000
         0           103.00000            46.80000             0.00000
         0            86.00000            46.80000             0.00000
         0            86.00000            36.80000             0.00000
         0            71.45000            36.80000             0.00000
         0            71.45000            46.80000             0.00000
         0            54.45000            46.80000             0.00000
         0            54.45000            36.80000             0.00000
         0            39.90000            36.80000             0.00000
         0            39.90000            46.80000             0.00000
         0            22.90000            46.80000             0.00000
         0            22.90000            36.80000             0.00000
         0             8.35000            36.80000             0.00000
         0             8.35000            46.80000             0.00000
         0             0.00000            46.80000             0.00000
         0             0.00000             1.00000             0.00000
         0             1.00000             0.00000            90.00000
         0           191.80000            -0.00000             0.00000
.END_PLACE_KEEPOUT
.PLACE_KEEPOUT      UNOWNED
TOP 2.00000        
         0           490.45000             0.00000             0.00000
         0           491.45000             1.00000            90.00000
         0           491.45000            46.80000             0.00000
         0           478.00000            46.80000             0.00000
         0           478.00000            36.80000             0.00000
         0           463.45000            36.80000             0.00000
         0           463.45000            46.80000             0.00000
         0           446.45000            46.80000             0.00000
         0           446.45000            36.80000             0.00000
         0           431.90000            36.80000             0.00000
         0           431.90000            46.80000             0.00000
         0           414.90000            46.80000             0.00000
         0           414.90000            36.80000             0.00000
         0           400.35000            36.80000             0.00000
         0           400.35000            46.80000             0.00000
         0           383.35000            46.80000             0.00000
         0           383.35000            36.80000             0.00000
         0           368.80000            36.80000             0.00000
         0           368.80000            46.80000             0.00000
         0           351.80000            46.80000             0.00000
         0           351.80000            36.80000             0.00000
         0           337.25000            36.80000             0.00000
         0           337.25000            46.80000             0.00000
         0           320.25000            46.80000             0.00000
         0           320.25000            36.80000             0.00000
         0           311.00000            36.80000             0.00000
         0           311.00000             1.00000             0.00000
         0           312.00000             0.00000            90.00000
         0           490.45000            -0.00000             0.00000
.END_PLACE_KEEPOUT
.PLACE_KEEPOUT      UNOWNED
TOP 2.00000        
         0            48.75000            14.00000             0.00000
         0            39.25000            14.00000           180.00000
         0            48.75000            14.00000           180.00000
.END_PLACE_KEEPOUT
.PLACE_KEEPOUT      UNOWNED
TOP 2.00000        
         0           111.85000            24.00000             0.00000
         0           102.35000            24.00000           180.00000
         0           111.85000            24.00000           180.00000
.END_PLACE_KEEPOUT
.PLACE_KEEPOUT      UNOWNED
TOP 2.00000        
         0           174.95000            14.00000             0.00000
         0           165.45000            14.00000           180.00000
         0           174.95000            14.00000           180.00000
.END_PLACE_KEEPOUT
.PLACE_KEEPOUT      UNOWNED
TOP 2.00000        
         0           346.05000            14.00000             0.00000
         0           336.55000            14.00000           180.00000
         0           346.05000            14.00000           180.00000
.END_PLACE_KEEPOUT
.PLACE_KEEPOUT      UNOWNED
TOP 2.00000        
         0           409.15000            24.00000             0.00000
         0           399.65000            24.00000           180.00000
         0           409.15000            24.00000           180.00000
.END_PLACE_KEEPOUT
.PLACE_KEEPOUT      UNOWNED
TOP 2.00000        
         0           472.25000            14.00000             0.00000
         0           462.75000            14.00000           180.00000
         0           472.25000            14.00000           180.00000
.END_PLACE_KEEPOUT
.PLACE_KEEPOUT      UNOWNED
TOP 2.00000        
         0           468.90000            31.00000             0.00000
         0           466.10000            31.00000           180.00000
         0           468.90000            31.00000           180.00000
.END_PLACE_KEEPOUT
.PLACE_KEEPOUT      UNOWNED
TOP 2.00000        
         0           342.70000            31.00000             0.00000
         0           339.90000            31.00000           180.00000
         0           342.70000            31.00000           180.00000
.END_PLACE_KEEPOUT
.PLACE_KEEPOUT      UNOWNED
TOP 2.00000        
         0            45.40000            31.00000             0.00000
         0            42.60000            31.00000           180.00000
         0            45.40000            31.00000           180.00000
.END_PLACE_KEEPOUT
.PLACE_KEEPOUT      UNOWNED
TOP 2.00000        
         0           171.60000            31.00000             0.00000
         0           168.80000            31.00000           180.00000
         0           171.60000            31.00000           180.00000
.END_PLACE_KEEPOUT
.PLACE_KEEPOUT      UNOWNED
TOP 0.20000        
         0           291.60000           260.00000             0.00000
         0           298.20000           260.00000             0.00000
         0           298.20000           386.00000             0.00000
         0           291.60000           386.00000             0.00000
         0           291.60000           260.00000             0.00000
.END_PLACE_KEEPOUT
.PLACE_KEEPOUT      UNOWNED
TOP 0.20000        
         0           191.80000           220.00000             0.00000
         0           198.40000           220.00000             0.00000
         0           198.40000           370.00000             0.00000
         0           198.00000           370.00000             0.00000
         0           198.00000           380.00000             0.00000
         0           199.00000           380.00000             0.00000
         0           198.00000           381.00000           -90.00000
         0           198.00000           385.00000             0.00000
         0           197.00000           386.00000            90.00000
         0           191.80000           386.00000             0.00000
         0           191.80000           220.00000             0.00000
.END_PLACE_KEEPOUT
.PLACE_KEEPOUT      UNOWNED
TOP 0.20000        
         0           191.80000           110.00000             0.00000
         0           198.40000           110.00000             0.00000
         0           198.40000           194.00000             0.00000
         0           191.80000           194.00000             0.00000
         0           191.80000           110.00000             0.00000
.END_PLACE_KEEPOUT
.PLACE_KEEPOUT      UNOWNED
TOP 0.20000        
         0           291.60000           110.00000             0.00000
         0           298.20000           110.00000             0.00000
         0           298.20000           234.00000             0.00000
         0           291.60000           234.00000             0.00000
         0           291.60000           110.00000             0.00000
.END_PLACE_KEEPOUT
.PLACE_KEEPOUT      UNOWNED
TOP 0.20000        
         0           291.60000            48.20000             0.00000
         0           298.20000            48.20000             0.00000
         0           298.20000            84.00000             0.00000
         0           291.60000            84.00000             0.00000
         0           291.60000            48.20000             0.00000
.END_PLACE_KEEPOUT
.PLACE_KEEPOUT      UNOWNED
TOP 0.20000        
         0           198.00000             0.00000             0.00000
         0           198.40000             0.08348            23.57818
         0           198.40000            84.00000             0.00000
         0           191.80000            84.00000             0.00000
         0           191.80000            -0.00000             0.00000
         0           198.00000            -0.00000             0.00000
.END_PLACE_KEEPOUT
.PLACE_KEEPOUT      UNOWNED
TOP 9.00000        
         0           289.70000           345.00000             0.00000
         0           289.70000           371.00000             0.00000
         0           276.75000           371.00000             0.00000
         0           276.75000           361.00000             0.00000
         0           275.75000           360.00000           -90.00000
         0           273.45000           360.00000             0.00000
         0           272.45000           361.00000           -90.00000
         0           272.45000           371.00000             0.00000
         0           252.00000           371.00000             0.00000
         0           252.00000           370.00000             0.00000
         0           200.30000           370.00000             0.00000
         0           200.30000           345.00000             0.00000
         0           245.00000           345.00000             0.00000
         0           289.70000           345.00000             0.00000
.END_PLACE_KEEPOUT
.PLACE_KEEPOUT      UNOWNED
TOP 10.10000       
         0           207.34000           303.16000             0.00000
         0           199.72000           303.16000             0.00000
         0           199.72000           312.53000             0.00000
         0           207.34000           312.53000             0.00000
         0           207.34000           303.16000             0.00000
.END_PLACE_KEEPOUT
.PLACE_KEEPOUT      UNOWNED
TOP 10.10000       
         0           288.62000           303.03000             0.00000
         0           281.00000           303.03000             0.00000
         0           281.00000           312.40000             0.00000
         0           288.62000           312.40000             0.00000
         0           288.62000           303.03000             0.00000
.END_PLACE_KEEPOUT
.PLACE_KEEPOUT      UNOWNED
TOP 10.10000       
         0           265.02000           193.80000             0.00000
         0           257.40000           193.80000             0.00000
         0           257.40000           203.17000             0.00000
         0           265.02000           203.17000             0.00000
         0           265.02000           193.80000             0.00000
.END_PLACE_KEEPOUT
.PLACE_KEEPOUT      UNOWNED
TOP 10.10000       
         0           209.61000           140.60000             0.00000
         0           201.99000           140.60000             0.00000
         0           201.99000           149.97000             0.00000
         0           209.61000           149.97000             0.00000
         0           209.61000           140.60000             0.00000
.END_PLACE_KEEPOUT
.PLACE_KEEPOUT      UNOWNED
TOP 10.10000       
         0           286.43000           100.21000             0.00000
         0           278.81000           100.21000             0.00000
         0           278.81000           109.58000             0.00000
         0           286.43000           109.58000             0.00000
         0           286.43000           100.21000             0.00000
.END_PLACE_KEEPOUT
.PLACE_KEEPOUT      UNOWNED
TOP 10.10000       
         0           210.78000           100.47000             0.00000
         0           203.16000           100.47000             0.00000
         0           203.16000           109.84000             0.00000
         0           210.78000           109.84000             0.00000
         0           210.78000           100.47000             0.00000
.END_PLACE_KEEPOUT
.PLACE_KEEPOUT      UNOWNED
TOP 3.80000        
         0           251.00000           336.00000             0.00000
         0           239.00000           336.00000             0.00000
         0           239.00000           345.00000             0.00000
         0           251.00000           345.00000             0.00000
         0           251.00000           336.00000             0.00000
.END_PLACE_KEEPOUT
.PLACE_KEEPOUT      UNOWNED
TOP 10.00000       
         0           191.80000           326.80000             0.00000
         0             0.00000           326.80000             0.00000
         0            -0.00000           370.00000             0.00000
         0             1.00000           371.00000           -90.00000
         0             2.00000           371.00000             0.00000
         0             3.00000           372.00000            90.00000
         0             3.00000           385.00000             0.00000
         0             4.00000           386.00000           -90.00000
         0            15.25000           386.00000             0.00000
         0            16.25000           385.00000           -90.00000
         0            16.25000           383.30000             0.00000
         0            17.25000           382.30000            90.00000
         0            23.75000           382.30000             0.00000
         0            24.75000           383.30000            90.00000
         0            24.75000           385.00000             0.00000
         0            25.75000           386.00000           -90.00000
         0            71.30000           386.00000             0.00000
         0            72.30000           385.00000           -90.00000
         0            72.30000           381.00000             0.00000
         0            73.30000           380.00000            90.00000
         0            72.30000           380.00000             0.00000
         0            72.30000           370.00000             0.00000
         0           126.30000           370.00000             0.00000
         0           126.30000           380.00000             0.00000
         0           125.30000           380.00000             0.00000
         0           126.30000           381.00000            90.00000
         0           126.30000           385.00000             0.00000
         0           127.30000           386.00000           -90.00000
         0           172.85000           386.00000             0.00000
         0           173.85000           385.00000           -90.00000
         0           173.85000           383.30000             0.00000
         0           174.85000           382.30000            90.00000
         0           181.35000           382.30000             0.00000
         0           182.35000           383.30000            90.00000
         0           182.35000           385.00000             0.00000
         0           183.35000           386.00000           -90.00000
         0           191.80000           386.00000             0.00000
         0           191.80000           326.80000             0.00000
.END_PLACE_KEEPOUT
.PLACE_KEEPOUT      UNOWNED
TOP 10.00000       
         0           317.15000           386.00000             0.00000
         0           316.15000           385.00000            90.00000
         0           316.15000           383.30000             0.00000
         0           315.15000           382.30000           -90.00000
         0           308.65000           382.30000             0.00000
         0           307.65000           383.30000           -90.00000
         0           307.65000           385.00000             0.00000
         0           306.65000           386.00000            90.00000
         0           298.20000           386.00000             0.00000
         0           298.20000           326.80000             0.00000
         0           491.45000           326.80000             0.00000
         0           491.45000           370.00000             0.00000
         0           490.45000           371.00000            90.00000
         0           489.45000           371.00000             0.00000
         0           488.45000           372.00000           -90.00000
         0           488.45000           385.00000             0.00000
         0           487.45000           386.00000            90.00000
         0           474.75000           386.00000             0.00000
         0           473.75000           385.00000            90.00000
         0           473.75000           383.30000             0.00000
         0           472.75000           382.30000           -90.00000
         0           466.25000           382.30000             0.00000
         0           465.25000           383.30000           -90.00000
         0           465.25000           385.00000             0.00000
         0           464.25000           386.00000            90.00000
         0           418.70000           386.00000             0.00000
         0           417.70000           385.00000            90.00000
         0           417.70000           381.00000             0.00000
         0           416.70000           380.00000           -90.00000
         0           417.70000           380.00000             0.00000
         0           417.70000           370.00000             0.00000
         0           363.70000           370.00000             0.00000
         0           363.70000           380.00000             0.00000
         0           364.70000           380.00000             0.00000
         0           363.70000           381.00000           -90.00000
         0           363.70000           385.00000             0.00000
         0           362.70000           386.00000            90.00000
         0           317.15000           386.00000             0.00000
.END_PLACE_KEEPOUT
.PLACE_KEEPOUT      UNOWNED
TOP 3.50000        
         0           291.60000           260.00000             0.00000
         0           291.60000           312.30000             0.00000
         0           288.62000           312.30000             0.00000
         0           288.62000           303.03000             0.00000
         0           281.00000           303.03000             0.00000
         0           281.00000           312.40000             0.00000
         0           288.62000           312.40000             0.00000
         0           291.60000           312.40000             0.00000
         0           291.60000           386.00000             0.00000
         0           280.16421           386.00000             0.00000
         0           279.45711           385.70711            45.00000
         0           277.04289           383.29289             0.00000
         0           276.75000           382.58579            45.00000
         0           276.75000           371.00000             0.00000
         0           289.70000           371.00000             0.00000
         0           289.70000           345.00000             0.00000
         0           251.00000           345.00000             0.00000
         0           251.00000           336.00000             0.00000
         0           239.00000           336.00000             0.00000
         0           239.00000           345.00000             0.00000
         0           200.30000           345.00000             0.00000
         0           200.30000           370.00000             0.00000
         0           198.40000           370.00000             0.00000
         0           198.40000           312.53000             0.00000
         0           199.72000           312.53000             0.00000
         0           207.34000           312.53000             0.00000
         0           207.34000           303.16000             0.00000
         0           199.72000           303.16000             0.00000
         0           199.72000           312.43000             0.00000
         0           198.40000           312.43000             0.00000
         0           198.40000           220.00000             0.00000
         0           202.30000           220.00000             0.00000
         0           202.30000           194.00000             0.00000
         0           198.40000           194.00000             0.00000
         0           198.40000           149.97000             0.00000
         0           201.99000           149.97000             0.00000
         0           209.61000           149.97000             0.00000
         0           209.61000           140.60000             0.00000
         0           201.99000           140.60000             0.00000
         0           201.99000           149.87000             0.00000
         0           198.40000           149.87000             0.00000
         0           198.40000           110.00000             0.00000
         0           202.30000           110.00000             0.00000
         0           202.30000           100.57000             0.00000
         0           203.16000           100.57000             0.00000
         0           203.16000           109.84000             0.00000
         0           210.78000           109.84000             0.00000
         0           210.78000           100.47000             0.00000
         0           203.16000           100.47000             0.00000
         0           202.30000           100.47000             0.00000
         0           202.30000            84.00000             0.00000
         0           198.40000            84.00000             0.00000
         0           198.40000             0.08348             0.00000
         0           199.00000             1.00000            66.42182
         0           199.00000            47.20000             0.00000
         0           200.00000            48.20000           -90.00000
         0           206.00000            48.20000             0.00000
         0           207.00000            49.20000            90.00000
         0           207.00000            62.00000             0.00000
         0           208.00000            63.00000           -90.00000
         0           268.00000            63.00000             0.00000
         0           269.00000            62.00000           -90.00000
         0           269.00000            49.20000             0.00000
         0           270.00000            48.20000            90.00000
         0           291.60000            48.20000             0.00000
         0           291.60000            84.00000             0.00000
         0           287.70000            84.00000             0.00000
         0           287.70000           100.21000             0.00000
         0           286.43000           100.21000             0.00000
         0           278.81000           100.21000             0.00000
         0           278.81000           109.58000             0.00000
         0           286.43000           109.58000             0.00000
         0           286.43000           100.31000             0.00000
         0           287.70000           100.31000             0.00000
         0           287.70000           110.00000             0.00000
         0           291.60000           110.00000             0.00000
         0           291.60000           203.07000             0.00000
         0           265.02000           203.07000             0.00000
         0           265.02000           193.80000             0.00000
         0           257.40000           193.80000             0.00000
         0           257.40000           203.17000             0.00000
         0           265.02000           203.17000             0.00000
         0           291.60000           203.17000             0.00000
         0           291.60000           234.00000             0.00000
         0           287.70000           234.00000             0.00000
         0           287.70000           260.00000             0.00000
         0           291.60000           260.00000             0.00000
.END_PLACE_KEEPOUT
.PLACE_KEEPOUT      UNOWNED
TOP 3.50000        
         0           272.45000           382.58579             0.00000
         0           272.15711           383.29289            45.00000
         0           269.74289           385.70711             0.00000
         0           269.03579           386.00000            45.00000
         0           253.00000           386.00000             0.00000
         0           252.00000           385.00000            90.00000
         0           252.00000           381.00000             0.00000
         0           251.00000           380.00000           -90.00000
         0           252.00000           380.00000             0.00000
         0           252.00000           371.00000             0.00000
         0           272.45000           371.00000             0.00000
         0           272.45000           382.58579             0.00000
.END_PLACE_KEEPOUT
.PLACE_KEEPOUT      UNOWNED
TOP 3.50000        
         0           276.80000           295.21000             0.00000
         0           284.30000           295.21000           180.00000
         0           276.80000           295.21000           180.00000
.END_PLACE_KEEPOUT
.PLACE_KEEPOUT      UNOWNED
TOP 3.50000        
         0           231.20000           234.00000             0.00000
         0           256.20000           234.00000             0.00000
         0           256.20000           260.00000             0.00000
         0           231.20000           260.00000             0.00000
         0           231.20000           234.00000             0.00000
.END_PLACE_KEEPOUT
.PLACE_KEEPOUT      UNOWNED
TOP 3.50000        
         0           256.20000           191.80000             0.00000
         0           231.20000           191.80000             0.00000
         0           231.20000           165.80000             0.00000
         0           256.20000           165.80000             0.00000
         0           256.20000           191.80000             0.00000
.END_PLACE_KEEPOUT
.PLACE_KEEPOUT      UNOWNED
BOTTOM 0.00000        
         0           152.32500           293.80000             0.00000
         0           152.32500           299.80000             0.00000
         0           166.32500           299.80000          -180.00000
         0           166.32500           293.80000             0.00000
         0           152.32500           293.80000          -180.00000
.END_PLACE_KEEPOUT
.PLACE_KEEPOUT      UNOWNED
BOTTOM 0.00000        
         0            89.32500           293.80000             0.00000
         0            89.32500           299.80000             0.00000
         0           103.32500           299.80000          -180.00000
         0           103.32500           293.80000             0.00000
         0            89.32500           293.80000          -180.00000
.END_PLACE_KEEPOUT
.PLACE_KEEPOUT      UNOWNED
BOTTOM 0.00000        
         0            26.32500           293.80000             0.00000
         0            26.32500           299.80000             0.00000
         0            40.32500           299.80000          -180.00000
         0            40.32500           293.80000             0.00000
         0            26.32500           293.80000          -180.00000
.END_PLACE_KEEPOUT
.PLACE_KEEPOUT      UNOWNED
BOTTOM 0.00000        
         0            26.32500           178.80000             0.00000
         0            26.32500           184.80000             0.00000
         0            40.32500           184.80000          -180.00000
         0            40.32500           178.80000             0.00000
         0            26.32500           178.80000          -180.00000
.END_PLACE_KEEPOUT
.PLACE_KEEPOUT      UNOWNED
BOTTOM 0.00000        
         0            89.32500           178.80000             0.00000
         0            89.32500           184.80000             0.00000
         0           103.32500           184.80000          -180.00000
         0           103.32500           178.80000             0.00000
         0            89.32500           178.80000          -180.00000
.END_PLACE_KEEPOUT
.PLACE_KEEPOUT      UNOWNED
BOTTOM 0.00000        
         0           152.32500           178.80000             0.00000
         0           152.32500           184.80000             0.00000
         0           166.32500           184.80000          -180.00000
         0           166.32500           178.80000             0.00000
         0           152.32500           178.80000          -180.00000
.END_PLACE_KEEPOUT
.PLACE_KEEPOUT      UNOWNED
BOTTOM 0.00000        
         0           182.80000           204.00000             0.00000
         0           182.80000           210.00000             0.00000
         0           196.80000           210.00000          -180.00000
         0           196.80000           204.00000             0.00000
         0           182.80000           204.00000          -180.00000
.END_PLACE_KEEPOUT
.PLACE_KEEPOUT      UNOWNED
BOTTOM 0.00000        
         0           293.20000           244.00000             0.00000
         0           293.20000           250.00000             0.00000
         0           307.20000           250.00000          -180.00000
         0           307.20000           244.00000             0.00000
         0           293.20000           244.00000          -180.00000
.END_PLACE_KEEPOUT
.PLACE_KEEPOUT      UNOWNED
BOTTOM 0.00000        
         0           237.20000           244.00000             0.00000
         0           237.20000           250.00000             0.00000
         0           251.20000           250.00000          -180.00000
         0           251.20000           244.00000             0.00000
         0           237.20000           244.00000          -180.00000
.END_PLACE_KEEPOUT
.PLACE_KEEPOUT      UNOWNED
BOTTOM 0.00000        
         0           386.67500           293.80000             0.00000
         0           386.67500           299.80000             0.00000
         0           400.67500           299.80000          -180.00000
         0           400.67500           293.80000             0.00000
         0           386.67500           293.80000          -180.00000
.END_PLACE_KEEPOUT
.PLACE_KEEPOUT      UNOWNED
BOTTOM 0.00000        
         0           323.67500           293.80000             0.00000
         0           323.67500           299.80000             0.00000
         0           337.67500           299.80000          -180.00000
         0           337.67500           293.80000             0.00000
         0           323.67500           293.80000          -180.00000
.END_PLACE_KEEPOUT
.PLACE_KEEPOUT      UNOWNED
BOTTOM 0.00000        
         0           449.67500           293.80000             0.00000
         0           449.67500           299.80000             0.00000
         0           463.67500           299.80000          -180.00000
         0           463.67500           293.80000             0.00000
         0           449.67500           293.80000          -180.00000
.END_PLACE_KEEPOUT
.PLACE_KEEPOUT      UNOWNED
BOTTOM 0.00000        
         0           449.67500           178.80000             0.00000
         0           449.67500           184.80000             0.00000
         0           463.67500           184.80000          -180.00000
         0           463.67500           178.80000             0.00000
         0           449.67500           178.80000          -180.00000
.END_PLACE_KEEPOUT
.PLACE_KEEPOUT      UNOWNED
BOTTOM 0.00000        
         0           386.67500           178.80000             0.00000
         0           386.67500           184.80000             0.00000
         0           400.67500           184.80000          -180.00000
         0           400.67500           178.80000             0.00000
         0           386.67500           178.80000          -180.00000
.END_PLACE_KEEPOUT
.PLACE_KEEPOUT      UNOWNED
BOTTOM 0.00000        
         0           323.67500           178.80000             0.00000
         0           323.67500           184.80000             0.00000
         0           337.67500           184.80000          -180.00000
         0           337.67500           178.80000             0.00000
         0           323.67500           178.80000          -180.00000
.END_PLACE_KEEPOUT
.PLACE_KEEPOUT      UNOWNED
BOTTOM 0.00000        
         0           237.20000           175.80000             0.00000
         0           237.20000           181.80000             0.00000
         0           251.20000           181.80000          -180.00000
         0           251.20000           175.80000             0.00000
         0           237.20000           175.80000          -180.00000
.END_PLACE_KEEPOUT
.PLACE_KEEPOUT      UNOWNED
BOTTOM 0.00000        
         0           293.20000            94.00000             0.00000
         0           293.20000           100.00000             0.00000
         0           307.20000           100.00000          -180.00000
         0           307.20000            94.00000             0.00000
         0           293.20000            94.00000          -180.00000
.END_PLACE_KEEPOUT
.PLACE_KEEPOUT      UNOWNED
BOTTOM 0.00000        
         0           323.67500            63.80000             0.00000
         0           323.67500            69.80000             0.00000
         0           337.67500            69.80000          -180.00000
         0           337.67500            63.80000             0.00000
         0           323.67500            63.80000          -180.00000
.END_PLACE_KEEPOUT
.PLACE_KEEPOUT      UNOWNED
BOTTOM 0.00000        
         0           386.67500            63.80000             0.00000
         0           386.67500            69.80000             0.00000
         0           400.67500            69.80000          -180.00000
         0           400.67500            63.80000             0.00000
         0           386.67500            63.80000          -180.00000
.END_PLACE_KEEPOUT
.PLACE_KEEPOUT      UNOWNED
BOTTOM 0.00000        
         0           449.67500            63.80000             0.00000
         0           449.67500            69.80000             0.00000
         0           463.67500            69.80000          -180.00000
         0           463.67500            63.80000             0.00000
         0           449.67500            63.80000          -180.00000
.END_PLACE_KEEPOUT
.PLACE_KEEPOUT      UNOWNED
BOTTOM 0.00000        
         0           182.80000            94.00000             0.00000
         0           182.80000           100.00000             0.00000
         0           196.80000           100.00000          -180.00000
         0           196.80000            94.00000             0.00000
         0           182.80000            94.00000          -180.00000
.END_PLACE_KEEPOUT
.PLACE_KEEPOUT      UNOWNED
BOTTOM 0.00000        
         0           152.32500            63.80000             0.00000
         0           152.32500            69.80000             0.00000
         0           166.32500            69.80000          -180.00000
         0           166.32500            63.80000             0.00000
         0           152.32500            63.80000          -180.00000
.END_PLACE_KEEPOUT
.PLACE_KEEPOUT      UNOWNED
BOTTOM 0.00000        
         0            89.32500            63.80000             0.00000
         0            89.32500            69.80000             0.00000
         0           103.32500            69.80000          -180.00000
         0           103.32500            63.80000             0.00000
         0            89.32500            63.80000          -180.00000
.END_PLACE_KEEPOUT
.PLACE_KEEPOUT      UNOWNED
BOTTOM 0.00000        
         0            26.32500            63.80000             0.00000
         0            26.32500            69.80000             0.00000
         0            40.32500            69.80000          -180.00000
         0            40.32500            63.80000             0.00000
         0            26.32500            63.80000          -180.00000
.END_PLACE_KEEPOUT
.PLACE_KEEPOUT      UNOWNED
BOTTOM 0.00000        
         0           284.30000           295.21000             0.00000
         0           276.80000           295.21000          -180.00000
         0           284.30000           295.21000          -180.00000
.END_PLACE_KEEPOUT
.PLACE_KEEPOUT      UNOWNED
BOTTOM 0.00000        
         0           135.00000           339.40000             0.00000
         0           135.00000           331.40000          -180.00000
         0           129.92000           331.40000             0.00000
         0           129.92000           339.40000          -180.00000
         0           135.00000           339.40000             0.00000
.END_PLACE_KEEPOUT
.PLACE_KEEPOUT      UNOWNED
BOTTOM 0.00000        
         0            67.70000           339.40000             0.00000
         0            67.70000           331.40000          -180.00000
         0            62.62000           331.40000             0.00000
         0            62.62000           339.40000          -180.00000
         0            67.70000           339.40000             0.00000
.END_PLACE_KEEPOUT
.PLACE_KEEPOUT      UNOWNED
BOTTOM 0.00000        
         0           439.17500            66.80000             0.00000
         0           411.17500            66.80000          -180.00000
         0           439.17500            66.80000          -180.00000
.END_PLACE_KEEPOUT
.PLACE_KEEPOUT      UNOWNED
BOTTOM 0.00000        
         0           141.82500           181.80000             0.00000
         0           113.82500           181.80000          -180.00000
         0           141.82500           181.80000          -180.00000
.END_PLACE_KEEPOUT
.PLACE_KEEPOUT      UNOWNED
BOTTOM 0.00000        
         0           417.06575            40.00000             0.00000
         0           398.39362            58.62945           -56.19895
         0           400.67500            63.80000            47.61655
         0           400.67500            69.80000             0.00000
         0           398.39362            74.97055            47.61655
         0           451.95638            74.97055          -146.06786
         0           449.67500            69.80000            47.61655
         0           449.67500            63.80000             0.00000
         0           451.95638            58.62945            47.61655
         0           433.28425            40.00000           -56.19895
         0           417.06575            40.00000             0.00000
.END_PLACE_KEEPOUT
.PLACE_KEEPOUT      UNOWNED
BOTTOM 0.00000        
         0           154.60638           173.62945             0.00000
         0           152.32500           178.80000           -47.61655
         0           152.32500           184.80000             0.00000
         0           154.60638           189.97055           -47.61655
         0           101.04362           189.97055           146.06786
         0           103.32500           184.80000           -47.61655
         0           103.32500           178.80000             0.00000
         0           101.04362           173.62945           -47.61655
         0           154.60638           173.62945           146.06786
.END_PLACE_KEEPOUT
.PLACE_KEEPOUT      UNOWNED
BOTTOM 0.00000        
         0           113.82500           181.80000             0.00000
         0           141.82500           181.80000          -180.00000
         0           113.82500           181.80000          -180.00000
.END_PLACE_KEEPOUT
.PLACE_KEEPOUT      UNOWNED
BOTTOM 0.00000        
         0           411.17500            66.80000             0.00000
         0           439.17500            66.80000          -180.00000
         0           411.17500            66.80000          -180.00000
.END_PLACE_KEEPOUT
.PLACE_KEEPOUT      UNOWNED
BOTTOM 2.00000        
         0           167.82500           181.80000             0.00000
         0            87.82500           181.80000          -180.00000
         0           167.82500           181.80000          -180.00000
.END_PLACE_KEEPOUT
.PLACE_KEEPOUT      UNOWNED
BOTTOM 2.00000        
         0            89.32500           184.80000             0.00000
         0           101.04362           189.97055          -132.38345
         0           154.60638           189.97055          -146.06786
         0           166.32500           184.80000          -132.38345
         0           166.32500           178.80000             0.00000
         0           154.60638           173.62945          -132.38345
         0           101.04362           173.62945          -146.06786
         0            89.32500           178.80000          -132.38345
         0            89.32500           184.80000             0.00000
.END_PLACE_KEEPOUT
.PLACE_KEEPOUT      UNOWNED
BOTTOM 2.00000        
         0           395.48056            40.00000             0.00000
         0           454.86944            40.00000          -264.13413
         0           433.28425            40.00000             0.00000
         0           451.95638            58.62945            56.19895
         0           463.67500            63.80000           132.38345
         0           463.67500            69.80000             0.00000
         0           451.95638            74.97055           132.38345
         0           398.39362            74.97055           146.06786
         0           386.67500            69.80000           132.38345
         0           386.67500            63.80000             0.00000
         0           398.39362            58.62945           132.38345
         0           417.06575            40.00000            56.19895
         0           395.48056            40.00000             0.00000
.END_PLACE_KEEPOUT
.PLACE_KEEPOUT      UNOWNED
BOTTOM 0.00000        
         0           199.00000             1.00000             0.00000
         0           198.00000             0.00000           -90.00000
         0             1.00000             0.00000             0.00000
         0             0.00000             1.00000           -90.00000
         0             0.00000            40.00000             0.00000
         0           199.00000            40.00000             0.00000
         0           199.00000             1.00000             0.00000
.END_PLACE_KEEPOUT
.PLACE_KEEPOUT      UNOWNED
BOTTOM 0.00000        
         0           491.45000             1.00000             0.00000
         0           490.45000             0.00000           -90.00000
         0           312.00000             0.00000             0.00000
         0           311.00000             1.00000           -90.00000
         0           311.00000            40.00000             0.00000
         0           491.45000            40.00000             0.00000
         0           491.45000             1.00000             0.00000
.END_PLACE_KEEPOUT
.PLACE_KEEPOUT      UNOWNED
BOTTOM 0.00000        
         0           417.70000           380.00000             0.00000
         0           417.70000           358.00000             0.00000
         0           363.70000           358.00000             0.00000
         0           363.70000           380.00000             0.00000
         0           417.70000           380.00000             0.00000
.END_PLACE_KEEPOUT
.PLACE_KEEPOUT      UNOWNED
BOTTOM 0.00000        
         0           198.00000           358.00000             0.00000
         0           198.00000           380.00000             0.00000
         0           252.00000           380.00000             0.00000
         0           252.00000           358.00000             0.00000
         0           198.00000           358.00000             0.00000
.END_PLACE_KEEPOUT
.PLACE_KEEPOUT      UNOWNED
BOTTOM 0.00000        
         0           126.30000           380.00000             0.00000
         0           126.30000           358.00000             0.00000
         0            72.30000           358.00000             0.00000
         0            72.30000           380.00000             0.00000
         0           126.30000           380.00000             0.00000
.END_PLACE_KEEPOUT
.PLACE_KEEPOUT      UNOWNED
BOTTOM 3.10000        
         0           454.86944            40.00000             0.00000
         0           491.45000            40.00000             0.00000
         0           491.45000           370.00000             0.00000
         0           490.45000           371.00000            90.00000
         0           489.45000           371.00000             0.00000
         0           488.45000           372.00000           -90.00000
         0           488.45000           385.00000             0.00000
         0           487.45000           386.00000            90.00000
         0           474.75000           386.00000             0.00000
         0           473.75000           385.00000            90.00000
         0           473.75000           383.30000             0.00000
         0           472.75000           382.30000           -90.00000
         0           466.25000           382.30000             0.00000
         0           465.25000           383.30000           -90.00000
         0           465.25000           385.00000             0.00000
         0           464.25000           386.00000            90.00000
         0           418.70000           386.00000             0.00000
         0           417.70000           385.00000            90.00000
         0           417.70000           381.00000             0.00000
         0           416.70000           380.00000           -90.00000
         0           417.70000           380.00000             0.00000
         0           417.70000           358.00000             0.00000
         0           363.70000           358.00000             0.00000
         0           363.70000           380.00000             0.00000
         0           364.70000           380.00000             0.00000
         0           363.70000           381.00000           -90.00000
         0           363.70000           385.00000             0.00000
         0           362.70000           386.00000            90.00000
         0           317.15000           386.00000             0.00000
         0           316.15000           385.00000            90.00000
         0           316.15000           383.30000             0.00000
         0           315.15000           382.30000           -90.00000
         0           308.65000           382.30000             0.00000
         0           307.65000           383.30000           -90.00000
         0           307.65000           385.00000             0.00000
         0           306.65000           386.00000            90.00000
         0           280.16421           386.00000             0.00000
         0           279.45711           385.70711            45.00000
         0           277.04289           383.29289             0.00000
         0           276.75000           382.58579            45.00000
         0           276.75000           361.00000             0.00000
         0           275.75000           360.00000           -90.00000
         0           273.45000           360.00000             0.00000
         0           272.45000           361.00000           -90.00000
         0           272.45000           382.58579             0.00000
         0           272.15711           383.29289            45.00000
         0           269.74289           385.70711             0.00000
         0           269.03579           386.00000            45.00000
         0           253.00000           386.00000             0.00000
         0           252.00000           385.00000            90.00000
         0           252.00000           381.00000             0.00000
         0           251.00000           380.00000           -90.00000
         0           252.00000           380.00000             0.00000
         0           252.00000           358.00000             0.00000
         0           198.00000           358.00000             0.00000
         0           198.00000           380.00000             0.00000
         0           199.00000           380.00000             0.00000
         0           198.00000           381.00000           -90.00000
         0           198.00000           385.00000             0.00000
         0           197.00000           386.00000            90.00000
         0           183.35000           386.00000             0.00000
         0           182.35000           385.00000            90.00000
         0           182.35000           383.30000             0.00000
         0           181.35000           382.30000           -90.00000
         0           174.85000           382.30000             0.00000
         0           173.85000           383.30000           -90.00000
         0           173.85000           385.00000             0.00000
         0           172.85000           386.00000            90.00000
         0           127.30000           386.00000             0.00000
         0           126.30000           385.00000            90.00000
         0           126.30000           381.00000             0.00000
         0           125.30000           380.00000           -90.00000
         0           126.30000           380.00000             0.00000
         0           126.30000           358.00000             0.00000
         0            72.30000           358.00000             0.00000
         0            72.30000           380.00000             0.00000
         0            73.30000           380.00000             0.00000
         0            72.30000           381.00000           -90.00000
         0            72.30000           385.00000             0.00000
         0            71.30000           386.00000            90.00000
         0            25.75000           386.00000             0.00000
         0            24.75000           385.00000            90.00000
         0            24.75000           383.30000             0.00000
         0            23.75000           382.30000           -90.00000
         0            17.25000           382.30000             0.00000
         0            16.25000           383.30000           -90.00000
         0            16.25000           385.00000             0.00000
         0            15.25000           386.00000            90.00000
         0             4.00000           386.00000             0.00000
         0             3.00000           385.00000            90.00000
         0             3.00000           372.00000             0.00000
         0             2.00000           371.00000           -90.00000
         0             1.00000           371.00000             0.00000
         0             0.00000           370.00000            90.00000
         0            -0.00000            40.00000             0.00000
         0           199.00000            40.00000             0.00000
         0           199.00000            47.20000             0.00000
         0           200.00000            48.20000           -90.00000
         0           206.00000            48.20000             0.00000
         0           207.00000            49.20000            90.00000
         0           207.00000            62.00000             0.00000
         0           208.00000            63.00000           -90.00000
         0           268.00000            63.00000             0.00000
         0           269.00000            62.00000           -90.00000
         0           269.00000            49.20000             0.00000
         0           270.00000            48.20000            90.00000
         0           310.00000            48.20000             0.00000
         0           311.00000            47.20000           -90.00000
         0           311.00000            40.00000             0.00000
         0           395.48056            40.00000             0.00000
         0           454.86944            40.00000          -264.13413
.END_PLACE_KEEPOUT
.PLACE_KEEPOUT      UNOWNED
BOTTOM 3.10000        
         0           463.67500           293.80000             0.00000
         0           449.67500           293.80000          -180.00000
         0           449.67500           299.80000             0.00000
         0           463.67500           299.80000          -180.00000
         0           463.67500           293.80000             0.00000
.END_PLACE_KEEPOUT
.PLACE_KEEPOUT      UNOWNED
BOTTOM 3.10000        
         0           400.67500           293.80000             0.00000
         0           386.67500           293.80000          -180.00000
         0           386.67500           299.80000             0.00000
         0           400.67500           299.80000          -180.00000
         0           400.67500           293.80000             0.00000
.END_PLACE_KEEPOUT
.PLACE_KEEPOUT      UNOWNED
BOTTOM 3.10000        
         0           337.67500           293.80000             0.00000
         0           323.67500           293.80000          -180.00000
         0           323.67500           299.80000             0.00000
         0           337.67500           299.80000          -180.00000
         0           337.67500           293.80000             0.00000
.END_PLACE_KEEPOUT
.PLACE_KEEPOUT      UNOWNED
BOTTOM 3.10000        
         0           276.80000           295.21000             0.00000
         0           284.30000           295.21000          -180.00000
         0           276.80000           295.21000          -180.00000
.END_PLACE_KEEPOUT
.PLACE_KEEPOUT      UNOWNED
BOTTOM 3.10000        
         0            40.32500           293.80000             0.00000
         0            40.32500           299.80000             0.00000
         0            26.32500           299.80000           180.00000
         0            26.32500           293.80000             0.00000
         0            40.32500           293.80000           180.00000
.END_PLACE_KEEPOUT
.PLACE_KEEPOUT      UNOWNED
BOTTOM 3.10000        
         0           103.32500           293.80000             0.00000
         0           103.32500           299.80000             0.00000
         0            89.32500           299.80000           180.00000
         0            89.32500           293.80000             0.00000
         0           103.32500           293.80000           180.00000
.END_PLACE_KEEPOUT
.PLACE_KEEPOUT      UNOWNED
BOTTOM 3.10000        
         0           166.32500           293.80000             0.00000
         0           166.32500           299.80000             0.00000
         0           152.32500           299.80000           180.00000
         0           152.32500           293.80000             0.00000
         0           166.32500           293.80000           180.00000
.END_PLACE_KEEPOUT
.PLACE_KEEPOUT      UNOWNED
BOTTOM 3.10000        
         0           251.20000           244.00000             0.00000
         0           251.20000           250.00000             0.00000
         0           237.20000           250.00000           180.00000
         0           237.20000           244.00000             0.00000
         0           251.20000           244.00000           180.00000
.END_PLACE_KEEPOUT
.PLACE_KEEPOUT      UNOWNED
BOTTOM 3.10000        
         0           196.80000           204.00000             0.00000
         0           196.80000           210.00000             0.00000
         0           182.80000           210.00000           180.00000
         0           182.80000           204.00000             0.00000
         0           196.80000           204.00000           180.00000
.END_PLACE_KEEPOUT
.PLACE_KEEPOUT      UNOWNED
BOTTOM 3.10000        
         0           463.67500           178.80000             0.00000
         0           463.67500           184.80000             0.00000
         0           449.67500           184.80000           180.00000
         0           449.67500           178.80000             0.00000
         0           463.67500           178.80000           180.00000
.END_PLACE_KEEPOUT
.PLACE_KEEPOUT      UNOWNED
BOTTOM 3.10000        
         0           400.67500           178.80000             0.00000
         0           400.67500           184.80000             0.00000
         0           386.67500           184.80000           180.00000
         0           386.67500           178.80000             0.00000
         0           400.67500           178.80000           180.00000
.END_PLACE_KEEPOUT
.PLACE_KEEPOUT      UNOWNED
BOTTOM 3.10000        
         0           307.20000           244.00000             0.00000
         0           307.20000           250.00000             0.00000
         0           293.20000           250.00000           180.00000
         0           293.20000           244.00000             0.00000
         0           307.20000           244.00000           180.00000
.END_PLACE_KEEPOUT
.PLACE_KEEPOUT      UNOWNED
BOTTOM 3.10000        
         0           337.67500           178.80000             0.00000
         0           337.67500           184.80000             0.00000
         0           323.67500           184.80000           180.00000
         0           323.67500           178.80000             0.00000
         0           337.67500           178.80000           180.00000
.END_PLACE_KEEPOUT
.PLACE_KEEPOUT      UNOWNED
BOTTOM 3.10000        
         0           251.20000           175.80000             0.00000
         0           251.20000           181.80000             0.00000
         0           237.20000           181.80000           180.00000
         0           237.20000           175.80000             0.00000
         0           251.20000           175.80000           180.00000
.END_PLACE_KEEPOUT
.PLACE_KEEPOUT      UNOWNED
BOTTOM 3.10000        
         0           337.67500            63.80000             0.00000
         0           337.67500            69.80000             0.00000
         0           323.67500            69.80000           180.00000
         0           323.67500            63.80000             0.00000
         0           337.67500            63.80000           180.00000
.END_PLACE_KEEPOUT
.PLACE_KEEPOUT      UNOWNED
BOTTOM 3.10000        
         0           307.20000            94.00000             0.00000
         0           307.20000           100.00000             0.00000
         0           293.20000           100.00000           180.00000
         0           293.20000            94.00000             0.00000
         0           307.20000            94.00000           180.00000
.END_PLACE_KEEPOUT
.PLACE_KEEPOUT      UNOWNED
BOTTOM 3.10000        
         0           196.80000            94.00000             0.00000
         0           196.80000           100.00000             0.00000
         0           182.80000           100.00000           180.00000
         0           182.80000            94.00000             0.00000
         0           196.80000            94.00000           180.00000
.END_PLACE_KEEPOUT
.PLACE_KEEPOUT      UNOWNED
BOTTOM 3.10000        
         0           166.32500            63.80000             0.00000
         0           166.32500            69.80000             0.00000
         0           152.32500            69.80000           180.00000
         0           152.32500            63.80000             0.00000
         0           166.32500            63.80000           180.00000
.END_PLACE_KEEPOUT
.PLACE_KEEPOUT      UNOWNED
BOTTOM 3.10000        
         0           103.32500            63.80000             0.00000
         0           103.32500            69.80000             0.00000
         0            89.32500            69.80000           180.00000
         0            89.32500            63.80000             0.00000
         0           103.32500            63.80000           180.00000
.END_PLACE_KEEPOUT
.PLACE_KEEPOUT      UNOWNED
BOTTOM 3.10000        
         0            87.82500           181.80000             0.00000
         0           167.82500           181.80000          -180.00000
         0            87.82500           181.80000          -180.00000
.END_PLACE_KEEPOUT
.PLACE_KEEPOUT      UNOWNED
BOTTOM 3.10000        
         0            40.32500           178.80000             0.00000
         0            40.32500           184.80000             0.00000
         0            26.32500           184.80000           180.00000
         0            26.32500           178.80000             0.00000
         0            40.32500           178.80000           180.00000
.END_PLACE_KEEPOUT
.PLACE_KEEPOUT      UNOWNED
BOTTOM 3.10000        
         0            40.32500            63.80000             0.00000
         0            40.32500            69.80000             0.00000
         0            26.32500            69.80000           180.00000
         0            26.32500            63.80000             0.00000
         0            40.32500            63.80000           180.00000
.END_PLACE_KEEPOUT
.PLACE_KEEPOUT      UNOWNED
BOTTOM 3.10000        
         0            62.62000           339.40000             0.00000
         0            67.70000           339.40000             0.00000
         0            67.70000           331.40000          -180.00000
         0            62.62000           331.40000             0.00000
         0            62.62000           339.40000          -180.00000
.END_PLACE_KEEPOUT
.PLACE_KEEPOUT      UNOWNED
BOTTOM 3.10000        
         0           129.92000           339.40000             0.00000
         0           135.00000           339.40000             0.00000
         0           135.00000           331.40000          -180.00000
         0           129.92000           331.40000             0.00000
         0           129.92000           339.40000          -180.00000
.END_PLACE_KEEPOUT
.ROUTE_KEEPOUT  UNOWNED
TOP
         0           337.67500           293.80000             0.00000
         0           337.67500           299.80000             0.00000
         0           323.67500           299.80000           180.00000
         0           323.67500           293.80000             0.00000
         0           337.67500           293.80000           180.00000
.END_ROUTE_KEEPOUT
.ROUTE_KEEPOUT  UNOWNED
TOP
         0           400.67500           293.80000             0.00000
         0           400.67500           299.80000             0.00000
         0           386.67500           299.80000           180.00000
         0           386.67500           293.80000             0.00000
         0           400.67500           293.80000           180.00000
.END_ROUTE_KEEPOUT
.ROUTE_KEEPOUT  UNOWNED
TOP
         0           463.67500           293.80000             0.00000
         0           463.67500           299.80000             0.00000
         0           449.67500           299.80000           180.00000
         0           449.67500           293.80000             0.00000
         0           463.67500           293.80000           180.00000
.END_ROUTE_KEEPOUT
.ROUTE_KEEPOUT  UNOWNED
TOP
         0           166.32500           293.80000             0.00000
         0           166.32500           299.80000             0.00000
         0           152.32500           299.80000           180.00000
         0           152.32500           293.80000             0.00000
         0           166.32500           293.80000           180.00000
.END_ROUTE_KEEPOUT
.ROUTE_KEEPOUT  UNOWNED
TOP
         0           103.32500           293.80000             0.00000
         0           103.32500           299.80000             0.00000
         0            89.32500           299.80000           180.00000
         0            89.32500           293.80000             0.00000
         0           103.32500           293.80000           180.00000
.END_ROUTE_KEEPOUT
.ROUTE_KEEPOUT  UNOWNED
TOP
         0            40.32500           293.80000             0.00000
         0            40.32500           299.80000             0.00000
         0            26.32500           299.80000           180.00000
         0            26.32500           293.80000             0.00000
         0            40.32500           293.80000           180.00000
.END_ROUTE_KEEPOUT
.ROUTE_KEEPOUT  UNOWNED
TOP
         0           293.20000           244.00000             0.00000
         0           307.20000           244.00000           180.00000
         0           307.20000           250.00000             0.00000
         0           293.20000           250.00000           180.00000
         0           293.20000           244.00000             0.00000
.END_ROUTE_KEEPOUT
.ROUTE_KEEPOUT  UNOWNED
TOP
         0           237.20000           244.00000             0.00000
         0           251.20000           244.00000           180.00000
         0           251.20000           250.00000             0.00000
         0           237.20000           250.00000           180.00000
         0           237.20000           244.00000             0.00000
.END_ROUTE_KEEPOUT
.ROUTE_KEEPOUT  UNOWNED
TOP
         0           237.20000           175.80000             0.00000
         0           251.20000           175.80000           180.00000
         0           251.20000           181.80000             0.00000
         0           237.20000           181.80000           180.00000
         0           237.20000           175.80000             0.00000
.END_ROUTE_KEEPOUT
.ROUTE_KEEPOUT  UNOWNED
TOP
         0           182.80000           204.00000             0.00000
         0           196.80000           204.00000           180.00000
         0           196.80000           210.00000             0.00000
         0           182.80000           210.00000           180.00000
         0           182.80000           204.00000             0.00000
.END_ROUTE_KEEPOUT
.ROUTE_KEEPOUT  UNOWNED
TOP
         0           323.67500           178.80000             0.00000
         0           337.67500           178.80000           180.00000
         0           337.67500           184.80000             0.00000
         0           323.67500           184.80000           180.00000
         0           323.67500           178.80000             0.00000
.END_ROUTE_KEEPOUT
.ROUTE_KEEPOUT  UNOWNED
TOP
         0           386.67500           178.80000             0.00000
         0           400.67500           178.80000           180.00000
         0           400.67500           184.80000             0.00000
         0           386.67500           184.80000           180.00000
         0           386.67500           178.80000             0.00000
.END_ROUTE_KEEPOUT
.ROUTE_KEEPOUT  UNOWNED
TOP
         0           449.67500           178.80000             0.00000
         0           463.67500           178.80000           180.00000
         0           463.67500           184.80000             0.00000
         0           449.67500           184.80000           180.00000
         0           449.67500           178.80000             0.00000
.END_ROUTE_KEEPOUT
.ROUTE_KEEPOUT  UNOWNED
TOP
         0           152.32500           178.80000             0.00000
         0           166.32500           178.80000           180.00000
         0           166.32500           184.80000             0.00000
         0           152.32500           184.80000           180.00000
         0           152.32500           178.80000             0.00000
.END_ROUTE_KEEPOUT
.ROUTE_KEEPOUT  UNOWNED
TOP
         0            89.32500           178.80000             0.00000
         0           103.32500           178.80000           180.00000
         0           103.32500           184.80000             0.00000
         0            89.32500           184.80000           180.00000
         0            89.32500           178.80000             0.00000
.END_ROUTE_KEEPOUT
.ROUTE_KEEPOUT  UNOWNED
TOP
         0            26.32500           178.80000             0.00000
         0            40.32500           178.80000           180.00000
         0            40.32500           184.80000             0.00000
         0            26.32500           184.80000           180.00000
         0            26.32500           178.80000             0.00000
.END_ROUTE_KEEPOUT
.ROUTE_KEEPOUT  UNOWNED
TOP
         0           293.20000            94.00000             0.00000
         0           307.20000            94.00000           180.00000
         0           307.20000           100.00000             0.00000
         0           293.20000           100.00000           180.00000
         0           293.20000            94.00000             0.00000
.END_ROUTE_KEEPOUT
.ROUTE_KEEPOUT  UNOWNED
TOP
         0           182.80000            94.00000             0.00000
         0           196.80000            94.00000           180.00000
         0           196.80000           100.00000             0.00000
         0           182.80000           100.00000           180.00000
         0           182.80000            94.00000             0.00000
.END_ROUTE_KEEPOUT
.ROUTE_KEEPOUT  UNOWNED
TOP
         0           152.32500            63.80000             0.00000
         0           166.32500            63.80000           180.00000
         0           166.32500            69.80000             0.00000
         0           152.32500            69.80000           180.00000
         0           152.32500            63.80000             0.00000
.END_ROUTE_KEEPOUT
.ROUTE_KEEPOUT  UNOWNED
TOP
         0            89.32500            63.80000             0.00000
         0           103.32500            63.80000           180.00000
         0           103.32500            69.80000             0.00000
         0            89.32500            69.80000           180.00000
         0            89.32500            63.80000             0.00000
.END_ROUTE_KEEPOUT
.ROUTE_KEEPOUT  UNOWNED
TOP
         0            26.32500            63.80000             0.00000
         0            40.32500            63.80000           180.00000
         0            40.32500            69.80000             0.00000
         0            26.32500            69.80000           180.00000
         0            26.32500            63.80000             0.00000
.END_ROUTE_KEEPOUT
.ROUTE_KEEPOUT  UNOWNED
TOP
         0           323.67500            63.80000             0.00000
         0           337.67500            63.80000           180.00000
         0           337.67500            69.80000             0.00000
         0           323.67500            69.80000           180.00000
         0           323.67500            63.80000             0.00000
.END_ROUTE_KEEPOUT
.ROUTE_KEEPOUT  UNOWNED
TOP
         0           386.67500            63.80000             0.00000
         0           400.67500            63.80000           180.00000
         0           400.67500            69.80000             0.00000
         0           386.67500            69.80000           180.00000
         0           386.67500            63.80000             0.00000
.END_ROUTE_KEEPOUT
.ROUTE_KEEPOUT  UNOWNED
TOP
         0           449.67500            63.80000             0.00000
         0           463.67500            63.80000           180.00000
         0           463.67500            69.80000             0.00000
         0           449.67500            69.80000           180.00000
         0           449.67500            63.80000             0.00000
.END_ROUTE_KEEPOUT
.ROUTE_KEEPOUT  UNOWNED
TOP
         0            39.25000            14.00000             0.00000
         0            48.75000            14.00000           180.00000
         0            39.25000            14.00000           180.00000
.END_ROUTE_KEEPOUT
.ROUTE_KEEPOUT  UNOWNED
TOP
         0           102.35000            24.00000             0.00000
         0           111.85000            24.00000           180.00000
         0           102.35000            24.00000           180.00000
.END_ROUTE_KEEPOUT
.ROUTE_KEEPOUT  UNOWNED
TOP
         0           165.45000            14.00000             0.00000
         0           174.95000            14.00000           180.00000
         0           165.45000            14.00000           180.00000
.END_ROUTE_KEEPOUT
.ROUTE_KEEPOUT  UNOWNED
TOP
         0           336.55000            14.00000             0.00000
         0           346.05000            14.00000           180.00000
         0           336.55000            14.00000           180.00000
.END_ROUTE_KEEPOUT
.ROUTE_KEEPOUT  UNOWNED
TOP
         0           399.65000            24.00000             0.00000
         0           409.15000            24.00000           180.00000
         0           399.65000            24.00000           180.00000
.END_ROUTE_KEEPOUT
.ROUTE_KEEPOUT  UNOWNED
TOP
         0           462.75000            14.00000             0.00000
         0           472.25000            14.00000           180.00000
         0           462.75000            14.00000           180.00000
.END_ROUTE_KEEPOUT
.ROUTE_KEEPOUT  UNOWNED
TOP
         0           141.82500           181.80000             0.00000
         0           113.82500           181.80000           180.00000
         0           141.82500           181.80000           180.00000
.END_ROUTE_KEEPOUT
.ROUTE_KEEPOUT  UNOWNED
TOP
         0           439.17500            66.80000             0.00000
         0           411.17500            66.80000           180.00000
         0           439.17500            66.80000           180.00000
.END_ROUTE_KEEPOUT
.ROUTE_KEEPOUT  UNOWNED
TOP
         0            67.70000           331.40000             0.00000
         0            67.70000           339.40000           180.00000
         0            62.62000           339.40000             0.00000
         0            62.62000           331.40000           180.00000
         0            67.70000           331.40000             0.00000
.END_ROUTE_KEEPOUT
.ROUTE_KEEPOUT  UNOWNED
TOP
         0           135.00000           331.40000             0.00000
         0           135.00000           339.40000           180.00000
         0           129.92000           339.40000             0.00000
         0           129.92000           331.40000           180.00000
         0           135.00000           331.40000             0.00000
.END_ROUTE_KEEPOUT
.ROUTE_KEEPOUT  UNOWNED
BOTTOM
         0           152.32500           293.80000             0.00000
         0           152.32500           299.80000             0.00000
         0           166.32500           299.80000          -180.00000
         0           166.32500           293.80000             0.00000
         0           152.32500           293.80000          -180.00000
.END_ROUTE_KEEPOUT
.ROUTE_KEEPOUT  UNOWNED
BOTTOM
         0            89.32500           293.80000             0.00000
         0            89.32500           299.80000             0.00000
         0           103.32500           299.80000          -180.00000
         0           103.32500           293.80000             0.00000
         0            89.32500           293.80000          -180.00000
.END_ROUTE_KEEPOUT
.ROUTE_KEEPOUT  UNOWNED
BOTTOM
         0            26.32500           293.80000             0.00000
         0            26.32500           299.80000             0.00000
         0            40.32500           299.80000          -180.00000
         0            40.32500           293.80000             0.00000
         0            26.32500           293.80000          -180.00000
.END_ROUTE_KEEPOUT
.ROUTE_KEEPOUT  UNOWNED
BOTTOM
         0           386.67500           293.80000             0.00000
         0           386.67500           299.80000             0.00000
         0           400.67500           299.80000          -180.00000
         0           400.67500           293.80000             0.00000
         0           386.67500           293.80000          -180.00000
.END_ROUTE_KEEPOUT
.ROUTE_KEEPOUT  UNOWNED
BOTTOM
         0           449.67500           293.80000             0.00000
         0           449.67500           299.80000             0.00000
         0           463.67500           299.80000          -180.00000
         0           463.67500           293.80000             0.00000
         0           449.67500           293.80000          -180.00000
.END_ROUTE_KEEPOUT
.ROUTE_KEEPOUT  UNOWNED
BOTTOM
         0           323.67500           293.80000             0.00000
         0           323.67500           299.80000             0.00000
         0           337.67500           299.80000          -180.00000
         0           337.67500           293.80000             0.00000
         0           323.67500           293.80000          -180.00000
.END_ROUTE_KEEPOUT
.ROUTE_KEEPOUT  UNOWNED
BOTTOM
         0           293.20000           244.00000             0.00000
         0           293.20000           250.00000             0.00000
         0           307.20000           250.00000          -180.00000
         0           307.20000           244.00000             0.00000
         0           293.20000           244.00000          -180.00000
.END_ROUTE_KEEPOUT
.ROUTE_KEEPOUT  UNOWNED
BOTTOM
         0           237.20000           244.00000             0.00000
         0           237.20000           250.00000             0.00000
         0           251.20000           250.00000          -180.00000
         0           251.20000           244.00000             0.00000
         0           237.20000           244.00000          -180.00000
.END_ROUTE_KEEPOUT
.ROUTE_KEEPOUT  UNOWNED
BOTTOM
         0           182.80000           204.00000             0.00000
         0           182.80000           210.00000             0.00000
         0           196.80000           210.00000          -180.00000
         0           196.80000           204.00000             0.00000
         0           182.80000           204.00000          -180.00000
.END_ROUTE_KEEPOUT
.ROUTE_KEEPOUT  UNOWNED
BOTTOM
         0           152.32500           178.80000             0.00000
         0           152.32500           184.80000             0.00000
         0           166.32500           184.80000          -180.00000
         0           166.32500           178.80000             0.00000
         0           152.32500           178.80000          -180.00000
.END_ROUTE_KEEPOUT
.ROUTE_KEEPOUT  UNOWNED
BOTTOM
         0            89.32500           178.80000             0.00000
         0            89.32500           184.80000             0.00000
         0           103.32500           184.80000          -180.00000
         0           103.32500           178.80000             0.00000
         0            89.32500           178.80000          -180.00000
.END_ROUTE_KEEPOUT
.ROUTE_KEEPOUT  UNOWNED
BOTTOM
         0            26.32500           178.80000             0.00000
         0            26.32500           184.80000             0.00000
         0            40.32500           184.80000          -180.00000
         0            40.32500           178.80000             0.00000
         0            26.32500           178.80000          -180.00000
.END_ROUTE_KEEPOUT
.ROUTE_KEEPOUT  UNOWNED
BOTTOM
         0           237.20000           175.80000             0.00000
         0           237.20000           181.80000             0.00000
         0           251.20000           181.80000          -180.00000
         0           251.20000           175.80000             0.00000
         0           237.20000           175.80000          -180.00000
.END_ROUTE_KEEPOUT
.ROUTE_KEEPOUT  UNOWNED
BOTTOM
         0           323.67500           178.80000             0.00000
         0           323.67500           184.80000             0.00000
         0           337.67500           184.80000          -180.00000
         0           337.67500           178.80000             0.00000
         0           323.67500           178.80000          -180.00000
.END_ROUTE_KEEPOUT
.ROUTE_KEEPOUT  UNOWNED
BOTTOM
         0           386.67500           178.80000             0.00000
         0           386.67500           184.80000             0.00000
         0           400.67500           184.80000          -180.00000
         0           400.67500           178.80000             0.00000
         0           386.67500           178.80000          -180.00000
.END_ROUTE_KEEPOUT
.ROUTE_KEEPOUT  UNOWNED
BOTTOM
         0           449.67500           178.80000             0.00000
         0           449.67500           184.80000             0.00000
         0           463.67500           184.80000          -180.00000
         0           463.67500           178.80000             0.00000
         0           449.67500           178.80000          -180.00000
.END_ROUTE_KEEPOUT
.ROUTE_KEEPOUT  UNOWNED
BOTTOM
         0           449.67500            63.80000             0.00000
         0           449.67500            69.80000             0.00000
         0           463.67500            69.80000          -180.00000
         0           463.67500            63.80000             0.00000
         0           449.67500            63.80000          -180.00000
.END_ROUTE_KEEPOUT
.ROUTE_KEEPOUT  UNOWNED
BOTTOM
         0           386.67500            63.80000             0.00000
         0           386.67500            69.80000             0.00000
         0           400.67500            69.80000          -180.00000
         0           400.67500            63.80000             0.00000
         0           386.67500            63.80000          -180.00000
.END_ROUTE_KEEPOUT
.ROUTE_KEEPOUT  UNOWNED
BOTTOM
         0           323.67500            63.80000             0.00000
         0           323.67500            69.80000             0.00000
         0           337.67500            69.80000          -180.00000
         0           337.67500            63.80000             0.00000
         0           323.67500            63.80000          -180.00000
.END_ROUTE_KEEPOUT
.ROUTE_KEEPOUT  UNOWNED
BOTTOM
         0           293.20000            94.00000             0.00000
         0           293.20000           100.00000             0.00000
         0           307.20000           100.00000          -180.00000
         0           307.20000            94.00000             0.00000
         0           293.20000            94.00000          -180.00000
.END_ROUTE_KEEPOUT
.ROUTE_KEEPOUT  UNOWNED
BOTTOM
         0           182.80000            94.00000             0.00000
         0           182.80000           100.00000             0.00000
         0           196.80000           100.00000          -180.00000
         0           196.80000            94.00000             0.00000
         0           182.80000            94.00000          -180.00000
.END_ROUTE_KEEPOUT
.ROUTE_KEEPOUT  UNOWNED
BOTTOM
         0           152.32500            63.80000             0.00000
         0           152.32500            69.80000             0.00000
         0           166.32500            69.80000          -180.00000
         0           166.32500            63.80000             0.00000
         0           152.32500            63.80000          -180.00000
.END_ROUTE_KEEPOUT
.ROUTE_KEEPOUT  UNOWNED
BOTTOM
         0            89.32500            63.80000             0.00000
         0            89.32500            69.80000             0.00000
         0           103.32500            69.80000          -180.00000
         0           103.32500            63.80000             0.00000
         0            89.32500            63.80000          -180.00000
.END_ROUTE_KEEPOUT
.ROUTE_KEEPOUT  UNOWNED
BOTTOM
         0            26.32500            63.80000             0.00000
         0            26.32500            69.80000             0.00000
         0            40.32500            69.80000          -180.00000
         0            40.32500            63.80000             0.00000
         0            26.32500            63.80000          -180.00000
.END_ROUTE_KEEPOUT
.ROUTE_KEEPOUT  UNOWNED
BOTTOM
         0           284.30000           295.21000             0.00000
         0           276.80000           295.21000          -180.00000
         0           284.30000           295.21000          -180.00000
.END_ROUTE_KEEPOUT
.ROUTE_KEEPOUT  UNOWNED
BOTTOM
         0            67.70000           339.40000             0.00000
         0            67.70000           331.40000          -180.00000
         0            62.62000           331.40000             0.00000
         0            62.62000           339.40000          -180.00000
         0            67.70000           339.40000             0.00000
.END_ROUTE_KEEPOUT
.ROUTE_KEEPOUT  UNOWNED
BOTTOM
         0           135.00000           339.40000             0.00000
         0           135.00000           331.40000          -180.00000
         0           129.92000           331.40000             0.00000
         0           129.92000           339.40000          -180.00000
         0           135.00000           339.40000             0.00000
.END_ROUTE_KEEPOUT
.ROUTE_KEEPOUT  UNOWNED
BOTTOM
         0           113.82500           181.80000             0.00000
         0           141.82500           181.80000          -180.00000
         0           113.82500           181.80000          -180.00000
.END_ROUTE_KEEPOUT
.ROUTE_KEEPOUT  UNOWNED
BOTTOM
         0           411.17500            66.80000             0.00000
         0           439.17500            66.80000          -180.00000
         0           411.17500            66.80000          -180.00000
.END_ROUTE_KEEPOUT
.ROUTE_KEEPOUT  UNOWNED
BOTTOM
         0           165.45000            14.00000             0.00000
         0           174.95000            14.00000          -180.00000
         0           165.45000            14.00000          -180.00000
.END_ROUTE_KEEPOUT
.ROUTE_KEEPOUT  UNOWNED
BOTTOM
         0           102.35000            24.00000             0.00000
         0           111.85000            24.00000          -180.00000
         0           102.35000            24.00000          -180.00000
.END_ROUTE_KEEPOUT
.ROUTE_KEEPOUT  UNOWNED
BOTTOM
         0            39.25000            14.00000             0.00000
         0            48.75000            14.00000          -180.00000
         0            39.25000            14.00000          -180.00000
.END_ROUTE_KEEPOUT
.ROUTE_KEEPOUT  UNOWNED
BOTTOM
         0           336.55000            14.00000             0.00000
         0           346.05000            14.00000          -180.00000
         0           336.55000            14.00000          -180.00000
.END_ROUTE_KEEPOUT
.ROUTE_KEEPOUT  UNOWNED
BOTTOM
         0           399.65000            24.00000             0.00000
         0           409.15000            24.00000          -180.00000
         0           399.65000            24.00000          -180.00000
.END_ROUTE_KEEPOUT
.ROUTE_KEEPOUT  UNOWNED
BOTTOM
         0           462.75000            14.00000             0.00000
         0           472.25000            14.00000          -180.00000
         0           462.75000            14.00000          -180.00000
.END_ROUTE_KEEPOUT
.PLACEMENT
062_10010_0121 062_10010_0121 HDDSAS30      
325.55000      28.91000       0.00000        270.00000      TOP       PLACED         
062_10010_0121 062_10010_0121 HDDSAS31      
357.10000      28.91000       0.00000        270.00000      TOP       PLACED         
062_10010_0121 062_10010_0121 HDDSAS32      
388.65000      28.91000       0.00000        270.00000      TOP       PLACED         
062_10010_0121 062_10010_0121 HDDSAS33      
420.20000      28.91000       0.00000        270.00000      TOP       PLACED         
062_10010_0121 062_10010_0121 HDDSAS34      
451.75000      28.91000       0.00000        270.00000      TOP       PLACED         
062_10010_0121 062_10010_0121 HDDSAS35      
483.30000      28.91000       0.00000        270.00000      TOP       PLACED         
062_10010_0121 062_10010_0121 HDDSAS18      
325.55000      143.91000      0.00000        270.00000      TOP       PLACED         
062_10010_0121 062_10010_0121 HDDSAS19      
357.10000      143.91000      0.00000        270.00000      TOP       PLACED         
062_10010_0121 062_10010_0121 HDDSAS20      
388.65000      143.91000      0.00000        270.00000      TOP       PLACED         
062_10010_0121 062_10010_0121 HDDSAS21      
420.20000      143.91000      0.00000        270.00000      TOP       PLACED         
062_10010_0121 062_10010_0121 HDDSAS22      
451.75000      143.91000      0.00000        270.00000      TOP       PLACED         
062_10010_0121 062_10010_0121 HDDSAS23      
483.30000      143.91000      0.00000        270.00000      TOP       PLACED         
062_10010_0121 062_10010_0121 HDDSAS6       
325.55000      258.91000      0.00000        270.00000      TOP       PLACED         
062_10010_0121 062_10010_0121 HDDSAS7       
357.10000      258.91000      0.00000        270.00000      TOP       PLACED         
062_10010_0121 062_10010_0121 HDDSAS8       
388.65000      258.91000      0.00000        270.00000      TOP       PLACED         
062_10010_0121 062_10010_0121 HDDSAS9       
420.20000      258.91000      0.00000        270.00000      TOP       PLACED         
062_10010_0121 062_10010_0121 HDDSAS10      
451.75000      258.91000      0.00000        270.00000      TOP       PLACED         
062_10010_0121 062_10010_0121 HDDSAS11      
483.30000      258.91000      0.00000        270.00000      TOP       PLACED         
062_10010_0121 062_10010_0121 HDDSAS24      
28.20000       28.91000       0.00000        270.00000      TOP       PLACED         
062_10010_0121 062_10010_0121 HDDSAS25      
59.75000       28.91000       0.00000        270.00000      TOP       PLACED         
062_10010_0121 062_10010_0121 HDDSAS26      
91.30000       28.91000       0.00000        270.00000      TOP       PLACED         
062_10010_0121 062_10010_0121 HDDSAS27      
122.85000      28.91000       0.00000        270.00000      TOP       PLACED         
062_10010_0121 062_10010_0121 HDDSAS28      
154.40000      28.91000       0.00000        270.00000      TOP       PLACED         
062_10010_0121 062_10010_0121 HDDSAS29      
185.95000      28.91000       0.00000        270.00000      TOP       PLACED         
062_10010_0121 062_10010_0121 HDDSAS12      
28.20000       143.91000      0.00000        270.00000      TOP       PLACED         
062_10010_0121 062_10010_0121 HDDSAS13      
59.75000       143.91000      0.00000        270.00000      TOP       PLACED         
062_10010_0121 062_10010_0121 HDDSAS14      
91.30000       143.91000      0.00000        270.00000      TOP       PLACED         
062_10010_0121 062_10010_0121 HDDSAS15      
122.85000      143.91000      0.00000        270.00000      TOP       PLACED         
062_10010_0121 062_10010_0121 HDDSAS16      
154.40000      143.91000      0.00000        270.00000      TOP       PLACED         
062_10010_0121 062_10010_0121 HDDSAS17      
185.95000      143.91000      0.00000        270.00000      TOP       PLACED         
062_10010_0121 062_10010_0121 HDDSAS0       
28.20000       258.91000      0.00000        270.00000      TOP       PLACED         
062_10010_0121 062_10010_0121 HDDSAS1       
59.75000       258.91000      0.00000        270.00000      TOP       PLACED         
062_10010_0121 062_10010_0121 HDDSAS2       
91.30000       258.91000      0.00000        270.00000      TOP       PLACED         
062_10010_0121 062_10010_0121 HDDSAS3       
122.85000      258.91000      0.00000        270.00000      TOP       PLACED         
062_10010_0121 062_10010_0121 HDDSAS4       
154.40000      258.91000      0.00000        270.00000      TOP       PLACED         
062_10010_0121 062_10010_0121 HDDSAS5       
185.95000      258.91000      0.00000        270.00000      TOP       PLACED         
083_00195_0B70 083_00195_0B70 LED18         
175.55000      65.40000       0.00000        0.00000        TOP       PLACED         
083_00195_0B70 083_00195_0B70 LED17         
144.00000      65.40000       0.00000        0.00000        TOP       PLACED         
083_00195_0B70 083_00195_0B70 LED16         
112.45000      65.40000       0.00000        0.00000        TOP       PLACED         
083_00195_0B70 083_00195_0B70 LED15         
80.90000       65.40000       0.00000        0.00000        TOP       PLACED         
083_00195_0B70 083_00195_0B70 LED14         
49.35000       65.40000       0.00000        0.00000        TOP       PLACED         
083_00195_0B70 083_00195_0B70 LED13         
17.80000       65.40000       0.00000        0.00000        TOP       PLACED         
083_00195_0B70 083_00195_0B70 LED6          
175.55000      180.40000      0.00000        0.00000        TOP       PLACED         
083_00195_0B70 083_00195_0B70 LED5          
144.00000      180.40000      0.00000        0.00000        TOP       PLACED         
083_00195_0B70 083_00195_0B70 LED4          
112.45000      180.40000      0.00000        0.00000        TOP       PLACED         
083_00195_0B70 083_00195_0B70 LED3          
80.90000       180.40000      0.00000        0.00000        TOP       PLACED         
083_00195_0B70 083_00195_0B70 LED2          
49.35000       180.40000      0.00000        0.00000        TOP       PLACED         
083_00195_0B70 083_00195_0B70 LED1          
17.80000       180.40000      0.00000        0.00000        TOP       PLACED         
083_00195_0B70 083_00195_0B70 LED24         
472.90000      65.40000       0.00000        0.00000        TOP       PLACED         
083_00195_0B70 083_00195_0B70 LED23         
441.35000      65.40000       0.00000        0.00000        TOP       PLACED         
083_00195_0B70 083_00195_0B70 LED22         
409.80000      65.40000       0.00000        0.00000        TOP       PLACED         
083_00195_0B70 083_00195_0B70 LED21         
378.25000      65.40000       0.00000        0.00000        TOP       PLACED         
083_00195_0B70 083_00195_0B70 LED20         
346.70000      65.40000       0.00000        0.00000        TOP       PLACED         
083_00195_0B70 083_00195_0B70 LED19         
315.15000      65.40000       0.00000        0.00000        TOP       PLACED         
083_00195_0B70 083_00195_0B70 LED12         
472.90000      180.40000      0.00000        0.00000        TOP       PLACED         
083_00195_0B70 083_00195_0B70 LED11         
441.35000      180.40000      0.00000        0.00000        TOP       PLACED         
083_00195_0B70 083_00195_0B70 LED10         
409.80000      180.40000      0.00000        0.00000        TOP       PLACED         
083_00195_0B70 083_00195_0B70 LED9          
378.25000      180.40000      0.00000        0.00000        TOP       PLACED         
083_00195_0B70 083_00195_0B70 LED8          
346.70000      180.40000      0.00000        0.00000        TOP       PLACED         
083_00195_0B70 083_00195_0B70 LED7          
315.15000      180.40000      0.00000        0.00000        TOP       PLACED         
020_80666_0010 020_80666_0010 FAN4          
439.00000      379.90000      0.00000        180.00000      TOP       PLACED         
020_80666_0010 020_80666_0010 FAN3          
342.40000      379.90000      0.00000        180.00000      TOP       PLACED         
020_80666_0010 020_80666_0010 FAN2          
147.60000      379.90000      0.00000        180.00000      TOP       PLACED         
020_80666_0010 020_80666_0010 FAN1          
51.00000       379.90000      0.00000        180.00000      TOP       PLACED         
ZZ_00PAD_PS1   ZZ_00PAD_PS1   PCIE1         
287.83660      144.69440      0.00000        270.00000      TOP       PLACED         
ZZ_00PAD_PN1   ZZ_00PAD_PN1   SAS1          
287.83670      238.69440      0.00000        270.00000      TOP       PLACED         
ZZ_PAD01_T21   ZZ_PAD01_T21   PWR1          
286.08670      287.69000      0.00000        270.00000      TOP       PLACED         
020_80657_0001 020_80657_0001 DPB2          
265.00000      65.00000       0.00000        180.00000      TOP       PLACED         
020_80829_0001 020_80829_0001 DPB1          
210.00000      66.80000       -0.00000       0.00000        TOP       PLACED         
06_WP130_14A   06_WP130_14A   FLED1         
20.50000       377.22000      0.00000        180.00000      TOP       PLACED         
06_WP130_14A   06_WP130_14A   FLED2         
178.10000      377.22000      0.00000        180.00000      TOP       PLACED         
06_WP130_14A   06_WP130_14A   FLED3         
311.90000      377.22000      0.00000        180.00000      TOP       PLACED         
06_WP130_14A   06_WP130_14A   FLED4         
469.50000      377.22000      0.00000        180.00000      TOP       PLACED         
083_04040_0070 083_04040_0070 LED25         
279.40000      378.00000      0.00000        180.00000      TOP       PLACED         
056_15005_0001 056_15005_0001 Q208          
269.80000      378.00000      0.00000        90.00000       TOP       PLACED         
086_000IZ_0543 086_000IZ_0543 SCW1          
127.82500      181.80000      -0.00000       0.00000        BOTTOM    PLACED         
086_000IZ_0543 086_000IZ_0543 SCW2          
425.17500      66.80000       -0.00000       0.00000        BOTTOM    PLACED         
020_8000B_0056 020_8000B_0056 BUS1          
67.70000       335.40000      0.00000        0.00000        TOP       PLACED         
.END_PLACEMENT
